FILE_TYPE = MACRO_DRAWING;
SET COLOR_WIRE YELLOW;
SET COLOR_PROP ORANGE;
SET COLOR_DOT WHITE;
SET COLOR_ARC YELLOW;
SET COLOR_BODY GREEN;
SET COLOR_NOTE PURPLE;
SET PROP_DISPLAY VALUE;
SET PAGE_NUMBER P461;
FORCEADD OFFPAGE..1
(-4375 2200);
FORCEPROP 2 LAST $XR0 353 
J 0
(-4627 2200);
DISPLAY 0.638298 (-4627 2200);
PAINT MONO (-4627 2200);
FORCEPROP 2 LAST CDS_LIB standard
J 0
(-4375 2200);
DISPLAY INVISIBLE (-4375 2200);
FORCEPROP 1 LAST OFFPAGE TRUE
J 0
(-4050 2075);
DISPLAY 0.872340 (-4050 2075);
DISPLAY INVISIBLE (-4050 2075);
FORCEPROP 1 LAST COMMENT_BODY TRUE
J 0
(-4250 2100);
DISPLAY 0.872340 (-4250 2100);
PAINT GREEN (-4250 2100);
DISPLAY INVISIBLE (-4250 2100);
FORCEPROP 2 LAST PATH I1
J 0
(-4625 2250);
DISPLAY 0.680851 (-4625 2250);
DISPLAY INVISIBLE (-4625 2250);
FORCEADD TAP..1
R 2
(-3425 1975);
FORCEPROP 3 LASTPIN (-3375 1975) SIG_NAME P5E_CPU1_P3_TX_BUF_DN<1>
J 0
(-3365 1985);
DISPLAY 0.659574 (-3365 1985);
PAINT MONO (-3365 1985);
DISPLAY INVISIBLE (-3365 1985);
FORCEPROP 1 LASTPIN (-3375 1975) BN 1
J 2
(-3363 1983);
DISPLAY 0.680851 (-3363 1983);
PAINT GREEN (-3363 1983);
FORCEPROP 2 LAST CDS_LIB standard
J 0
(-3425 1975);
DISPLAY INVISIBLE (-3425 1975);
FORCEPROP 1 LAST BODY_TYPE PLUMBING
J 2
(-3425 2025);
DISPLAY 0.872340 (-3425 2025);
PAINT GREEN (-3425 2025);
DISPLAY INVISIBLE (-3425 2025);
FORCEPROP 1 LAST HDL_TAP TRUE
J 2
(-3750 1850);
DISPLAY 0.872340 (-3750 1850);
DISPLAY INVISIBLE (-3750 1850);
FORCEPROP 1 LAST PATH I10
J 2
(-3423 1975);
DISPLAY 0.872340 (-3423 1975);
PAINT GREEN (-3423 1975);
DISPLAY INVISIBLE (-3423 1975);
FORCEADD Q_CAP_DIFFBUS..2
R 2
(-7025 1850);
FORCEPROP 1 LAST LOCATION C6744
J 2
(-6750 1850);
DISPLAY 0.723404 (-6750 1850);
PAINT GREEN (-6750 1850);
FORCEPROP 2 LAST $SEC 1
J 2
(-6850 1925);
DISPLAY 0.680851 (-6850 1925);
PAINT MONO (-6850 1925);
DISPLAY INVISIBLE (-6850 1925);
FORCEPROP 2 LAST CDS_SEC 1
J 2
(-6850 1925);
DISPLAY 0.680851 (-6850 1925);
DISPLAY INVISIBLE (-6850 1925);
FORCEPROP 2 LASTPIN (-6950 1850) $PN 1
J 0
(-6940 1860);
DISPLAY 0.808511 (-6940 1860);
FORCEPROP 2 LASTPIN (-7100 1850) $PN 2
J 2
(-7110 1860);
DISPLAY 0.808511 (-7110 1860);
FORCEPROP 2 LAST VALUE DIFF BUS_0.22UF
J 2
(-7175 1850);
DISPLAY 0.553191 (-7175 1850);
FORCEPROP 2 LAST TOLERANCE 20%
J 2
(-7100 1900);
DISPLAY 0.553191 (-7100 1900);
DISPLAY INVISIBLE (-7100 1900);
FORCEPROP 2 LAST PACK_TYPE C0201
J 2
(-7200 1900);
DISPLAY 0.553191 (-7200 1900);
DISPLAY INVISIBLE (-7200 1900);
FORCEPROP 1 LAST MATERIAL X6S
J 2
(-7016 1929);
DISPLAY 0.574468 (-7016 1929);
PAINT GREEN (-7016 1929);
DISPLAY INVISIBLE (-7016 1929);
FORCEPROP 2 LAST VOLTAGE 6.3V
J 2
(-7375 1900);
DISPLAY 0.553191 (-7375 1900);
DISPLAY INVISIBLE (-7375 1900);
FORCEPROP 1 LAST PIN_NAMES_ROTATE TRUE
J 2
(-7025 1850);
DISPLAY 0.489362 (-7025 1850);
PAINT GREEN (-7025 1850);
DISPLAY INVISIBLE (-7025 1850);
FORCEPROP 2 LAST CDS_LIB pure_quanta
J 2
(-7025 1850);
DISPLAY INVISIBLE (-7025 1850);
FORCEPROP 1 LAST CDS_LMAN_SYM_OUTLINE -25,50,25,-50
J 2
(-7025 1850);
DISPLAY 0.468085 (-7025 1850);
PAINT GREEN (-7025 1850);
DISPLAY INVISIBLE (-7025 1850);
FORCEPROP 1 LAST PATH I100
J 2
(-7025 1850);
DISPLAY 0.723404 (-7025 1850);
DISPLAY INVISIBLE (-7025 1850);
FORCEPROP 1 LAST PART_NUMBER SP_CH4221MEE01
J 2
(-7141 1938);
DISPLAY 0.574468 (-7141 1938);
PAINT GREEN (-7141 1938);
DISPLAY INVISIBLE (-7141 1938);
FORCEPROP 1 LAST LOCATION C6744
J 0
(-6775 1925);
DISPLAY 1.021277 (-6775 1925);
DISPLAY INVISIBLE (-6775 1925);
FORCEADD Q_CAP_DIFFBUS..2
R 2
(-7025 1900);
FORCEPROP 1 LAST LOCATION C6743
J 2
(-6750 1900);
DISPLAY 0.723404 (-6750 1900);
PAINT GREEN (-6750 1900);
FORCEPROP 2 LAST $SEC 1
J 2
(-6850 1975);
DISPLAY 0.680851 (-6850 1975);
PAINT MONO (-6850 1975);
DISPLAY INVISIBLE (-6850 1975);
FORCEPROP 2 LAST CDS_SEC 1
J 2
(-6850 1975);
DISPLAY 0.680851 (-6850 1975);
DISPLAY INVISIBLE (-6850 1975);
FORCEPROP 2 LASTPIN (-6950 1900) $PN 1
J 0
(-6940 1910);
DISPLAY 0.808511 (-6940 1910);
FORCEPROP 2 LASTPIN (-7100 1900) $PN 2
J 2
(-7110 1910);
DISPLAY 0.808511 (-7110 1910);
FORCEPROP 2 LAST VALUE DIFF BUS_0.22UF
J 2
(-7175 1900);
DISPLAY 0.553191 (-7175 1900);
FORCEPROP 2 LAST TOLERANCE 20%
J 2
(-7100 1950);
DISPLAY 0.553191 (-7100 1950);
DISPLAY INVISIBLE (-7100 1950);
FORCEPROP 2 LAST PACK_TYPE C0201
J 2
(-7200 1950);
DISPLAY 0.553191 (-7200 1950);
DISPLAY INVISIBLE (-7200 1950);
FORCEPROP 1 LAST MATERIAL X6S
J 2
(-7016 1979);
DISPLAY 0.574468 (-7016 1979);
PAINT GREEN (-7016 1979);
DISPLAY INVISIBLE (-7016 1979);
FORCEPROP 2 LAST VOLTAGE 6.3V
J 2
(-7375 1950);
DISPLAY 0.553191 (-7375 1950);
DISPLAY INVISIBLE (-7375 1950);
FORCEPROP 1 LAST PIN_NAMES_ROTATE TRUE
J 2
(-7025 1900);
DISPLAY 0.489362 (-7025 1900);
PAINT GREEN (-7025 1900);
DISPLAY INVISIBLE (-7025 1900);
FORCEPROP 2 LAST CDS_LIB pure_quanta
J 2
(-7025 1900);
DISPLAY INVISIBLE (-7025 1900);
FORCEPROP 1 LAST CDS_LMAN_SYM_OUTLINE -25,50,25,-50
J 2
(-7025 1900);
DISPLAY 0.468085 (-7025 1900);
PAINT GREEN (-7025 1900);
DISPLAY INVISIBLE (-7025 1900);
FORCEPROP 1 LAST PATH I101
J 2
(-7025 1900);
DISPLAY 0.723404 (-7025 1900);
DISPLAY INVISIBLE (-7025 1900);
FORCEPROP 1 LAST PART_NUMBER SP_CH4221MEE01
J 2
(-7141 1988);
DISPLAY 0.574468 (-7141 1988);
PAINT GREEN (-7141 1988);
DISPLAY INVISIBLE (-7141 1988);
FORCEPROP 1 LAST LOCATION C6743
J 0
(-6775 1975);
DISPLAY 1.021277 (-6775 1975);
DISPLAY INVISIBLE (-6775 1975);
FORCEADD TAP..1
R 2
(-8000 2050);
FORCEPROP 3 LASTPIN (-7950 2050) SIG_NAME P5E_CPU1_P3_TX_BUF_DN<8>
J 0
(-7940 2060);
DISPLAY 0.659574 (-7940 2060);
PAINT MONO (-7940 2060);
DISPLAY INVISIBLE (-7940 2060);
FORCEPROP 1 LASTPIN (-7950 2050) BN 8
J 2
(-7938 2058);
DISPLAY 0.680851 (-7938 2058);
PAINT GREEN (-7938 2058);
FORCEPROP 2 LAST CDS_LIB standard
J 0
(-8000 2050);
DISPLAY INVISIBLE (-8000 2050);
FORCEPROP 1 LAST BODY_TYPE PLUMBING
J 2
(-8000 2100);
DISPLAY 0.872340 (-8000 2100);
PAINT GREEN (-8000 2100);
DISPLAY INVISIBLE (-8000 2100);
FORCEPROP 1 LAST HDL_TAP TRUE
J 2
(-8325 1925);
DISPLAY 0.872340 (-8325 1925);
DISPLAY INVISIBLE (-8325 1925);
FORCEPROP 1 LAST PATH I102
J 2
(-7998 2050);
DISPLAY 0.872340 (-7998 2050);
PAINT GREEN (-7998 2050);
DISPLAY INVISIBLE (-7998 2050);
FORCEADD TAP..1
R 2
(-7750 2100);
FORCEPROP 3 LASTPIN (-7700 2100) SIG_NAME P5E_CPU1_P3_TX_BUF_DP<8>
J 0
(-7690 2110);
DISPLAY 0.659574 (-7690 2110);
PAINT MONO (-7690 2110);
DISPLAY INVISIBLE (-7690 2110);
FORCEPROP 1 LASTPIN (-7700 2100) BN 8
J 2
(-7688 2108);
DISPLAY 0.680851 (-7688 2108);
PAINT GREEN (-7688 2108);
FORCEPROP 2 LAST CDS_LIB standard
J 0
(-7750 2100);
DISPLAY INVISIBLE (-7750 2100);
FORCEPROP 1 LAST BODY_TYPE PLUMBING
J 2
(-7750 2150);
DISPLAY 0.872340 (-7750 2150);
PAINT GREEN (-7750 2150);
DISPLAY INVISIBLE (-7750 2150);
FORCEPROP 1 LAST HDL_TAP TRUE
J 2
(-8075 1975);
DISPLAY 0.872340 (-8075 1975);
DISPLAY INVISIBLE (-8075 1975);
FORCEPROP 1 LAST PATH I103
J 2
(-7748 2100);
DISPLAY 0.872340 (-7748 2100);
PAINT GREEN (-7748 2100);
DISPLAY INVISIBLE (-7748 2100);
FORCEADD Q_CAP_DIFFBUS..2
R 2
(-7025 2050);
FORCEPROP 1 LAST LOCATION C6742
J 2
(-6750 2050);
DISPLAY 0.723404 (-6750 2050);
PAINT GREEN (-6750 2050);
FORCEPROP 2 LAST $SEC 1
J 2
(-6850 2125);
DISPLAY 0.680851 (-6850 2125);
PAINT MONO (-6850 2125);
DISPLAY INVISIBLE (-6850 2125);
FORCEPROP 2 LAST CDS_SEC 1
J 2
(-6850 2125);
DISPLAY 0.680851 (-6850 2125);
DISPLAY INVISIBLE (-6850 2125);
FORCEPROP 2 LASTPIN (-6950 2050) $PN 1
J 0
(-6940 2060);
DISPLAY 0.808511 (-6940 2060);
FORCEPROP 2 LASTPIN (-7100 2050) $PN 2
J 2
(-7110 2060);
DISPLAY 0.808511 (-7110 2060);
FORCEPROP 2 LAST VALUE DIFF BUS_0.22UF
J 2
(-7175 2050);
DISPLAY 0.553191 (-7175 2050);
FORCEPROP 2 LAST TOLERANCE 20%
J 2
(-7100 2100);
DISPLAY 0.553191 (-7100 2100);
DISPLAY INVISIBLE (-7100 2100);
FORCEPROP 2 LAST PACK_TYPE C0201
J 2
(-7200 2100);
DISPLAY 0.553191 (-7200 2100);
DISPLAY INVISIBLE (-7200 2100);
FORCEPROP 1 LAST MATERIAL X6S
J 2
(-7016 2129);
DISPLAY 0.574468 (-7016 2129);
PAINT GREEN (-7016 2129);
DISPLAY INVISIBLE (-7016 2129);
FORCEPROP 2 LAST VOLTAGE 6.3V
J 2
(-7375 2100);
DISPLAY 0.553191 (-7375 2100);
DISPLAY INVISIBLE (-7375 2100);
FORCEPROP 1 LAST PIN_NAMES_ROTATE TRUE
J 2
(-7025 2050);
DISPLAY 0.489362 (-7025 2050);
PAINT GREEN (-7025 2050);
DISPLAY INVISIBLE (-7025 2050);
FORCEPROP 2 LAST CDS_LIB pure_quanta
J 2
(-7025 2050);
DISPLAY INVISIBLE (-7025 2050);
FORCEPROP 1 LAST CDS_LMAN_SYM_OUTLINE -25,50,25,-50
J 2
(-7025 2050);
DISPLAY 0.468085 (-7025 2050);
PAINT GREEN (-7025 2050);
DISPLAY INVISIBLE (-7025 2050);
FORCEPROP 1 LAST PATH I104
J 2
(-7025 2050);
DISPLAY 0.723404 (-7025 2050);
DISPLAY INVISIBLE (-7025 2050);
FORCEPROP 1 LAST PART_NUMBER SP_CH4221MEE01
J 2
(-7141 2138);
DISPLAY 0.574468 (-7141 2138);
PAINT GREEN (-7141 2138);
DISPLAY INVISIBLE (-7141 2138);
FORCEPROP 1 LAST LOCATION C6742
J 0
(-6775 2125);
DISPLAY 1.021277 (-6775 2125);
DISPLAY INVISIBLE (-6775 2125);
FORCEADD Q_CAP_DIFFBUS..2
R 2
(-7025 2100);
FORCEPROP 1 LAST LOCATION C6741
J 2
(-6750 2100);
DISPLAY 0.723404 (-6750 2100);
PAINT GREEN (-6750 2100);
FORCEPROP 2 LAST $SEC 1
J 2
(-6850 2175);
DISPLAY 0.680851 (-6850 2175);
PAINT MONO (-6850 2175);
DISPLAY INVISIBLE (-6850 2175);
FORCEPROP 2 LAST CDS_SEC 1
J 2
(-6850 2175);
DISPLAY 0.680851 (-6850 2175);
DISPLAY INVISIBLE (-6850 2175);
FORCEPROP 2 LASTPIN (-6950 2100) $PN 1
J 0
(-6940 2110);
DISPLAY 0.808511 (-6940 2110);
FORCEPROP 2 LASTPIN (-7100 2100) $PN 2
J 2
(-7110 2110);
DISPLAY 0.808511 (-7110 2110);
FORCEPROP 2 LAST VALUE DIFF BUS_0.22UF
J 2
(-7175 2100);
DISPLAY 0.553191 (-7175 2100);
FORCEPROP 2 LAST TOLERANCE 20%
J 2
(-6975 2250);
DISPLAY 0.553191 (-6975 2250);
PAINT GREEN (-6975 2250);
FORCEPROP 2 LAST PACK_TYPE C0201
J 2
(-7075 2250);
DISPLAY 0.553191 (-7075 2250);
PAINT GREEN (-7075 2250);
FORCEPROP 1 LAST MATERIAL X6S
J 2
(-7116 2304);
DISPLAY 0.574468 (-7116 2304);
PAINT GREEN (-7116 2304);
FORCEPROP 2 LAST VOLTAGE 6.3V
J 2
(-6850 2250);
DISPLAY 0.553191 (-6850 2250);
PAINT GREEN (-6850 2250);
FORCEPROP 1 LAST PIN_NAMES_ROTATE TRUE
J 2
(-7025 2100);
DISPLAY 0.489362 (-7025 2100);
PAINT GREEN (-7025 2100);
DISPLAY INVISIBLE (-7025 2100);
FORCEPROP 1 LAST CDS_LMAN_SYM_OUTLINE -25,50,25,-50
J 2
(-7025 2100);
DISPLAY 0.468085 (-7025 2100);
PAINT GREEN (-7025 2100);
DISPLAY INVISIBLE (-7025 2100);
FORCEPROP 2 LAST CDS_LIB pure_quanta
J 2
(-7025 2100);
DISPLAY INVISIBLE (-7025 2100);
FORCEPROP 1 LAST PATH I105
J 2
(-7025 2100);
DISPLAY 0.723404 (-7025 2100);
DISPLAY INVISIBLE (-7025 2100);
FORCEPROP 1 LAST PART_NUMBER SP_CH4221MEE01
J 2
(-6841 2188);
DISPLAY 0.574468 (-6841 2188);
PAINT GREEN (-6841 2188);
DISPLAY INVISIBLE (-6841 2188);
FORCEPROP 1 LAST LOCATION C6741
J 0
(-6775 2175);
DISPLAY 1.021277 (-6775 2175);
DISPLAY INVISIBLE (-6775 2175);
FORCEADD TAP..1
(-6475 700);
FORCEPROP 3 LASTPIN (-6525 700) SIG_NAME P5E_CPU1_P3_TX_BUF_C_DP<15>
J 0
(-6515 710);
DISPLAY 0.659574 (-6515 710);
PAINT MONO (-6515 710);
DISPLAY INVISIBLE (-6515 710);
FORCEPROP 1 LASTPIN (-6525 700) BN 15
J 0
(-6537 708);
DISPLAY 0.680851 (-6537 708);
PAINT GREEN (-6537 708);
FORCEPROP 2 LAST CDS_LIB standard
J 0
(-6475 700);
DISPLAY INVISIBLE (-6475 700);
FORCEPROP 1 LAST BODY_TYPE PLUMBING
J 0
(-6475 750);
DISPLAY 0.872340 (-6475 750);
PAINT GREEN (-6475 750);
DISPLAY INVISIBLE (-6475 750);
FORCEPROP 1 LAST HDL_TAP TRUE
J 0
(-6150 575);
DISPLAY 0.872340 (-6150 575);
DISPLAY INVISIBLE (-6150 575);
FORCEPROP 1 LAST PATH I106
J 0
(-6477 700);
DISPLAY 0.872340 (-6477 700);
PAINT GREEN (-6477 700);
DISPLAY INVISIBLE (-6477 700);
FORCEADD TAP..1
(-6475 900);
FORCEPROP 3 LASTPIN (-6525 900) SIG_NAME P5E_CPU1_P3_TX_BUF_C_DP<14>
J 0
(-6515 910);
DISPLAY 0.659574 (-6515 910);
PAINT MONO (-6515 910);
DISPLAY INVISIBLE (-6515 910);
FORCEPROP 1 LASTPIN (-6525 900) BN 14
J 0
(-6537 908);
DISPLAY 0.680851 (-6537 908);
PAINT GREEN (-6537 908);
FORCEPROP 2 LAST CDS_LIB standard
J 0
(-6475 900);
DISPLAY INVISIBLE (-6475 900);
FORCEPROP 1 LAST BODY_TYPE PLUMBING
J 0
(-6475 950);
DISPLAY 0.872340 (-6475 950);
PAINT GREEN (-6475 950);
DISPLAY INVISIBLE (-6475 950);
FORCEPROP 1 LAST HDL_TAP TRUE
J 0
(-6150 775);
DISPLAY 0.872340 (-6150 775);
DISPLAY INVISIBLE (-6150 775);
FORCEPROP 1 LAST PATH I107
J 0
(-6477 900);
DISPLAY 0.872340 (-6477 900);
PAINT GREEN (-6477 900);
DISPLAY INVISIBLE (-6477 900);
FORCEADD TAP..1
(-6275 650);
FORCEPROP 3 LASTPIN (-6325 650) SIG_NAME P5E_CPU1_P3_TX_BUF_C_DN<15>
J 0
(-6315 660);
DISPLAY 0.659574 (-6315 660);
PAINT MONO (-6315 660);
DISPLAY INVISIBLE (-6315 660);
FORCEPROP 1 LASTPIN (-6325 650) BN 15
J 0
(-6337 658);
DISPLAY 0.680851 (-6337 658);
PAINT GREEN (-6337 658);
FORCEPROP 2 LAST CDS_LIB standard
J 0
(-6275 650);
DISPLAY INVISIBLE (-6275 650);
FORCEPROP 1 LAST BODY_TYPE PLUMBING
J 0
(-6275 700);
DISPLAY 0.872340 (-6275 700);
PAINT GREEN (-6275 700);
DISPLAY INVISIBLE (-6275 700);
FORCEPROP 1 LAST HDL_TAP TRUE
J 0
(-5950 525);
DISPLAY 0.872340 (-5950 525);
DISPLAY INVISIBLE (-5950 525);
FORCEPROP 1 LAST PATH I108
J 0
(-6277 650);
DISPLAY 0.872340 (-6277 650);
PAINT GREEN (-6277 650);
DISPLAY INVISIBLE (-6277 650);
FORCEADD TAP..1
(-6275 850);
FORCEPROP 3 LASTPIN (-6325 850) SIG_NAME P5E_CPU1_P3_TX_BUF_C_DN<14>
J 0
(-6315 860);
DISPLAY 0.659574 (-6315 860);
PAINT MONO (-6315 860);
DISPLAY INVISIBLE (-6315 860);
FORCEPROP 1 LASTPIN (-6325 850) BN 14
J 0
(-6337 858);
DISPLAY 0.680851 (-6337 858);
PAINT GREEN (-6337 858);
FORCEPROP 2 LAST CDS_LIB standard
J 0
(-6275 850);
DISPLAY INVISIBLE (-6275 850);
FORCEPROP 1 LAST BODY_TYPE PLUMBING
J 0
(-6275 900);
DISPLAY 0.872340 (-6275 900);
PAINT GREEN (-6275 900);
DISPLAY INVISIBLE (-6275 900);
FORCEPROP 1 LAST HDL_TAP TRUE
J 0
(-5950 725);
DISPLAY 0.872340 (-5950 725);
DISPLAY INVISIBLE (-5950 725);
FORCEPROP 1 LAST PATH I109
J 0
(-6277 850);
DISPLAY 0.872340 (-6277 850);
PAINT GREEN (-6277 850);
DISPLAY INVISIBLE (-6277 850);
FORCEADD TAP..1
R 2
(-3175 1225);
FORCEPROP 3 LASTPIN (-3125 1225) SIG_NAME P5E_CPU1_P3_TX_BUF_DP<5>
J 0
(-3115 1235);
DISPLAY 0.659574 (-3115 1235);
PAINT MONO (-3115 1235);
DISPLAY INVISIBLE (-3115 1235);
FORCEPROP 1 LASTPIN (-3125 1225) BN 5
J 2
(-3113 1233);
DISPLAY 0.680851 (-3113 1233);
PAINT GREEN (-3113 1233);
FORCEPROP 2 LAST CDS_LIB standard
J 0
(-3175 1225);
DISPLAY INVISIBLE (-3175 1225);
FORCEPROP 1 LAST BODY_TYPE PLUMBING
J 2
(-3175 1275);
DISPLAY 0.872340 (-3175 1275);
PAINT GREEN (-3175 1275);
DISPLAY INVISIBLE (-3175 1275);
FORCEPROP 1 LAST HDL_TAP TRUE
J 2
(-3500 1100);
DISPLAY 0.872340 (-3500 1100);
DISPLAY INVISIBLE (-3500 1100);
FORCEPROP 1 LAST PATH I11
J 2
(-3173 1225);
DISPLAY 0.872340 (-3173 1225);
PAINT GREEN (-3173 1225);
DISPLAY INVISIBLE (-3173 1225);
FORCEADD TAP..1
(-6475 1100);
FORCEPROP 3 LASTPIN (-6525 1100) SIG_NAME P5E_CPU1_P3_TX_BUF_C_DP<13>
J 0
(-6515 1110);
DISPLAY 0.659574 (-6515 1110);
PAINT MONO (-6515 1110);
DISPLAY INVISIBLE (-6515 1110);
FORCEPROP 1 LASTPIN (-6525 1100) BN 13
J 0
(-6537 1108);
DISPLAY 0.680851 (-6537 1108);
PAINT GREEN (-6537 1108);
FORCEPROP 2 LAST CDS_LIB standard
J 0
(-6475 1100);
DISPLAY INVISIBLE (-6475 1100);
FORCEPROP 1 LAST BODY_TYPE PLUMBING
J 0
(-6475 1150);
DISPLAY 0.872340 (-6475 1150);
PAINT GREEN (-6475 1150);
DISPLAY INVISIBLE (-6475 1150);
FORCEPROP 1 LAST HDL_TAP TRUE
J 0
(-6150 975);
DISPLAY 0.872340 (-6150 975);
DISPLAY INVISIBLE (-6150 975);
FORCEPROP 1 LAST PATH I110
J 0
(-6477 1100);
DISPLAY 0.872340 (-6477 1100);
PAINT GREEN (-6477 1100);
DISPLAY INVISIBLE (-6477 1100);
FORCEADD TAP..1
(-6475 1300);
FORCEPROP 3 LASTPIN (-6525 1300) SIG_NAME P5E_CPU1_P3_TX_BUF_C_DP<12>
J 0
(-6515 1310);
DISPLAY 0.659574 (-6515 1310);
PAINT MONO (-6515 1310);
DISPLAY INVISIBLE (-6515 1310);
FORCEPROP 1 LASTPIN (-6525 1300) BN 12
J 0
(-6537 1308);
DISPLAY 0.680851 (-6537 1308);
PAINT GREEN (-6537 1308);
FORCEPROP 2 LAST CDS_LIB standard
J 0
(-6475 1300);
DISPLAY INVISIBLE (-6475 1300);
FORCEPROP 1 LAST BODY_TYPE PLUMBING
J 0
(-6475 1350);
DISPLAY 0.872340 (-6475 1350);
PAINT GREEN (-6475 1350);
DISPLAY INVISIBLE (-6475 1350);
FORCEPROP 1 LAST HDL_TAP TRUE
J 0
(-6150 1175);
DISPLAY 0.872340 (-6150 1175);
DISPLAY INVISIBLE (-6150 1175);
FORCEPROP 1 LAST PATH I111
J 0
(-6477 1300);
DISPLAY 0.872340 (-6477 1300);
PAINT GREEN (-6477 1300);
DISPLAY INVISIBLE (-6477 1300);
FORCEADD TAP..1
(-6275 1050);
FORCEPROP 3 LASTPIN (-6325 1050) SIG_NAME P5E_CPU1_P3_TX_BUF_C_DN<13>
J 0
(-6315 1060);
DISPLAY 0.659574 (-6315 1060);
PAINT MONO (-6315 1060);
DISPLAY INVISIBLE (-6315 1060);
FORCEPROP 1 LASTPIN (-6325 1050) BN 13
J 0
(-6337 1058);
DISPLAY 0.680851 (-6337 1058);
PAINT GREEN (-6337 1058);
FORCEPROP 2 LAST CDS_LIB standard
J 0
(-6275 1050);
DISPLAY INVISIBLE (-6275 1050);
FORCEPROP 1 LAST BODY_TYPE PLUMBING
J 0
(-6275 1100);
DISPLAY 0.872340 (-6275 1100);
PAINT GREEN (-6275 1100);
DISPLAY INVISIBLE (-6275 1100);
FORCEPROP 1 LAST HDL_TAP TRUE
J 0
(-5950 925);
DISPLAY 0.872340 (-5950 925);
DISPLAY INVISIBLE (-5950 925);
FORCEPROP 1 LAST PATH I112
J 0
(-6277 1050);
DISPLAY 0.872340 (-6277 1050);
PAINT GREEN (-6277 1050);
DISPLAY INVISIBLE (-6277 1050);
FORCEADD TAP..1
(-6275 1250);
FORCEPROP 3 LASTPIN (-6325 1250) SIG_NAME P5E_CPU1_P3_TX_BUF_C_DN<12>
J 0
(-6315 1260);
DISPLAY 0.659574 (-6315 1260);
PAINT MONO (-6315 1260);
DISPLAY INVISIBLE (-6315 1260);
FORCEPROP 1 LASTPIN (-6325 1250) BN 12
J 0
(-6337 1258);
DISPLAY 0.680851 (-6337 1258);
PAINT GREEN (-6337 1258);
FORCEPROP 2 LAST CDS_LIB standard
J 0
(-6275 1250);
DISPLAY INVISIBLE (-6275 1250);
FORCEPROP 1 LAST BODY_TYPE PLUMBING
J 0
(-6275 1300);
DISPLAY 0.872340 (-6275 1300);
PAINT GREEN (-6275 1300);
DISPLAY INVISIBLE (-6275 1300);
FORCEPROP 1 LAST HDL_TAP TRUE
J 0
(-5950 1125);
DISPLAY 0.872340 (-5950 1125);
DISPLAY INVISIBLE (-5950 1125);
FORCEPROP 1 LAST PATH I113
J 0
(-6277 1250);
DISPLAY 0.872340 (-6277 1250);
PAINT GREEN (-6277 1250);
DISPLAY INVISIBLE (-6277 1250);
FORCEADD TAP..1
(-6475 1500);
FORCEPROP 3 LASTPIN (-6525 1500) SIG_NAME P5E_CPU1_P3_TX_BUF_C_DP<11>
J 0
(-6515 1510);
DISPLAY 0.659574 (-6515 1510);
PAINT MONO (-6515 1510);
DISPLAY INVISIBLE (-6515 1510);
FORCEPROP 1 LASTPIN (-6525 1500) BN 11
J 0
(-6537 1508);
DISPLAY 0.680851 (-6537 1508);
PAINT GREEN (-6537 1508);
FORCEPROP 2 LAST CDS_LIB standard
J 0
(-6475 1500);
DISPLAY INVISIBLE (-6475 1500);
FORCEPROP 1 LAST BODY_TYPE PLUMBING
J 0
(-6475 1550);
DISPLAY 0.872340 (-6475 1550);
PAINT GREEN (-6475 1550);
DISPLAY INVISIBLE (-6475 1550);
FORCEPROP 1 LAST HDL_TAP TRUE
J 0
(-6150 1375);
DISPLAY 0.872340 (-6150 1375);
DISPLAY INVISIBLE (-6150 1375);
FORCEPROP 1 LAST PATH I114
J 0
(-6477 1500);
DISPLAY 0.872340 (-6477 1500);
PAINT GREEN (-6477 1500);
DISPLAY INVISIBLE (-6477 1500);
FORCEADD TAP..1
(-6475 1700);
FORCEPROP 3 LASTPIN (-6525 1700) SIG_NAME P5E_CPU1_P3_TX_BUF_C_DP<10>
J 0
(-6515 1710);
DISPLAY 0.659574 (-6515 1710);
PAINT MONO (-6515 1710);
DISPLAY INVISIBLE (-6515 1710);
FORCEPROP 1 LASTPIN (-6525 1700) BN 10
J 0
(-6537 1708);
DISPLAY 0.680851 (-6537 1708);
PAINT GREEN (-6537 1708);
FORCEPROP 2 LAST CDS_LIB standard
J 0
(-6475 1700);
DISPLAY INVISIBLE (-6475 1700);
FORCEPROP 1 LAST BODY_TYPE PLUMBING
J 0
(-6475 1750);
DISPLAY 0.872340 (-6475 1750);
PAINT GREEN (-6475 1750);
DISPLAY INVISIBLE (-6475 1750);
FORCEPROP 1 LAST HDL_TAP TRUE
J 0
(-6150 1575);
DISPLAY 0.872340 (-6150 1575);
DISPLAY INVISIBLE (-6150 1575);
FORCEPROP 1 LAST PATH I115
J 0
(-6477 1700);
DISPLAY 0.872340 (-6477 1700);
PAINT GREEN (-6477 1700);
DISPLAY INVISIBLE (-6477 1700);
FORCEADD TAP..1
(-6475 1900);
FORCEPROP 3 LASTPIN (-6525 1900) SIG_NAME P5E_CPU1_P3_TX_BUF_C_DP<9>
J 0
(-6515 1910);
DISPLAY 0.659574 (-6515 1910);
PAINT MONO (-6515 1910);
DISPLAY INVISIBLE (-6515 1910);
FORCEPROP 1 LASTPIN (-6525 1900) BN 9
J 0
(-6537 1908);
DISPLAY 0.680851 (-6537 1908);
PAINT GREEN (-6537 1908);
FORCEPROP 2 LAST CDS_LIB standard
J 0
(-6475 1900);
DISPLAY INVISIBLE (-6475 1900);
FORCEPROP 1 LAST BODY_TYPE PLUMBING
J 0
(-6475 1950);
DISPLAY 0.872340 (-6475 1950);
PAINT GREEN (-6475 1950);
DISPLAY INVISIBLE (-6475 1950);
FORCEPROP 1 LAST HDL_TAP TRUE
J 0
(-6150 1775);
DISPLAY 0.872340 (-6150 1775);
DISPLAY INVISIBLE (-6150 1775);
FORCEPROP 1 LAST PATH I116
J 0
(-6477 1900);
DISPLAY 0.872340 (-6477 1900);
PAINT GREEN (-6477 1900);
DISPLAY INVISIBLE (-6477 1900);
FORCEADD TAP..1
(-6275 1450);
FORCEPROP 3 LASTPIN (-6325 1450) SIG_NAME P5E_CPU1_P3_TX_BUF_C_DN<11>
J 0
(-6315 1460);
DISPLAY 0.659574 (-6315 1460);
PAINT MONO (-6315 1460);
DISPLAY INVISIBLE (-6315 1460);
FORCEPROP 1 LASTPIN (-6325 1450) BN 11
J 0
(-6337 1458);
DISPLAY 0.680851 (-6337 1458);
PAINT GREEN (-6337 1458);
FORCEPROP 2 LAST CDS_LIB standard
J 0
(-6275 1450);
DISPLAY INVISIBLE (-6275 1450);
FORCEPROP 1 LAST BODY_TYPE PLUMBING
J 0
(-6275 1500);
DISPLAY 0.872340 (-6275 1500);
PAINT GREEN (-6275 1500);
DISPLAY INVISIBLE (-6275 1500);
FORCEPROP 1 LAST HDL_TAP TRUE
J 0
(-5950 1325);
DISPLAY 0.872340 (-5950 1325);
DISPLAY INVISIBLE (-5950 1325);
FORCEPROP 1 LAST PATH I117
J 0
(-6277 1450);
DISPLAY 0.872340 (-6277 1450);
PAINT GREEN (-6277 1450);
DISPLAY INVISIBLE (-6277 1450);
FORCEADD TAP..1
(-6275 1650);
FORCEPROP 3 LASTPIN (-6325 1650) SIG_NAME P5E_CPU1_P3_TX_BUF_C_DN<10>
J 0
(-6315 1660);
DISPLAY 0.659574 (-6315 1660);
PAINT MONO (-6315 1660);
DISPLAY INVISIBLE (-6315 1660);
FORCEPROP 1 LASTPIN (-6325 1650) BN 10
J 0
(-6337 1658);
DISPLAY 0.680851 (-6337 1658);
PAINT GREEN (-6337 1658);
FORCEPROP 2 LAST CDS_LIB standard
J 0
(-6275 1650);
DISPLAY INVISIBLE (-6275 1650);
FORCEPROP 1 LAST BODY_TYPE PLUMBING
J 0
(-6275 1700);
DISPLAY 0.872340 (-6275 1700);
PAINT GREEN (-6275 1700);
DISPLAY INVISIBLE (-6275 1700);
FORCEPROP 1 LAST HDL_TAP TRUE
J 0
(-5950 1525);
DISPLAY 0.872340 (-5950 1525);
DISPLAY INVISIBLE (-5950 1525);
FORCEPROP 1 LAST PATH I118
J 0
(-6277 1650);
DISPLAY 0.872340 (-6277 1650);
PAINT GREEN (-6277 1650);
DISPLAY INVISIBLE (-6277 1650);
FORCEADD TAP..1
(-6275 1850);
FORCEPROP 3 LASTPIN (-6325 1850) SIG_NAME P5E_CPU1_P3_TX_BUF_C_DN<9>
J 0
(-6315 1860);
DISPLAY 0.659574 (-6315 1860);
PAINT MONO (-6315 1860);
DISPLAY INVISIBLE (-6315 1860);
FORCEPROP 1 LASTPIN (-6325 1850) BN 9
J 0
(-6337 1858);
DISPLAY 0.680851 (-6337 1858);
PAINT GREEN (-6337 1858);
FORCEPROP 2 LAST CDS_LIB standard
J 0
(-6275 1850);
DISPLAY INVISIBLE (-6275 1850);
FORCEPROP 1 LAST BODY_TYPE PLUMBING
J 0
(-6275 1900);
DISPLAY 0.872340 (-6275 1900);
PAINT GREEN (-6275 1900);
DISPLAY INVISIBLE (-6275 1900);
FORCEPROP 1 LAST HDL_TAP TRUE
J 0
(-5950 1725);
DISPLAY 0.872340 (-5950 1725);
DISPLAY INVISIBLE (-5950 1725);
FORCEPROP 1 LAST PATH I119
J 0
(-6277 1850);
DISPLAY 0.872340 (-6277 1850);
PAINT GREEN (-6277 1850);
DISPLAY INVISIBLE (-6277 1850);
FORCEADD TAP..1
R 2
(-3175 1025);
FORCEPROP 3 LASTPIN (-3125 1025) SIG_NAME P5E_CPU1_P3_TX_BUF_DP<6>
J 0
(-3115 1035);
DISPLAY 0.659574 (-3115 1035);
PAINT MONO (-3115 1035);
DISPLAY INVISIBLE (-3115 1035);
FORCEPROP 1 LASTPIN (-3125 1025) BN 6
J 2
(-3113 1033);
DISPLAY 0.680851 (-3113 1033);
PAINT GREEN (-3113 1033);
FORCEPROP 2 LAST CDS_LIB standard
J 0
(-3175 1025);
DISPLAY INVISIBLE (-3175 1025);
FORCEPROP 1 LAST BODY_TYPE PLUMBING
J 2
(-3175 1075);
DISPLAY 0.872340 (-3175 1075);
PAINT GREEN (-3175 1075);
DISPLAY INVISIBLE (-3175 1075);
FORCEPROP 1 LAST HDL_TAP TRUE
J 2
(-3500 900);
DISPLAY 0.872340 (-3500 900);
DISPLAY INVISIBLE (-3500 900);
FORCEPROP 1 LAST PATH I12
J 2
(-3173 1025);
DISPLAY 0.872340 (-3173 1025);
PAINT GREEN (-3173 1025);
DISPLAY INVISIBLE (-3173 1025);
FORCEADD TAP..1
(-6475 2100);
FORCEPROP 3 LASTPIN (-6525 2100) SIG_NAME P5E_CPU1_P3_TX_BUF_C_DP<8>
J 0
(-6515 2110);
DISPLAY 0.659574 (-6515 2110);
PAINT MONO (-6515 2110);
DISPLAY INVISIBLE (-6515 2110);
FORCEPROP 1 LASTPIN (-6525 2100) BN 8
J 0
(-6537 2108);
DISPLAY 0.680851 (-6537 2108);
PAINT GREEN (-6537 2108);
FORCEPROP 2 LAST CDS_LIB standard
J 0
(-6475 2100);
DISPLAY INVISIBLE (-6475 2100);
FORCEPROP 1 LAST BODY_TYPE PLUMBING
J 0
(-6475 2150);
DISPLAY 0.872340 (-6475 2150);
PAINT GREEN (-6475 2150);
DISPLAY INVISIBLE (-6475 2150);
FORCEPROP 1 LAST HDL_TAP TRUE
J 0
(-6150 1975);
DISPLAY 0.872340 (-6150 1975);
DISPLAY INVISIBLE (-6150 1975);
FORCEPROP 1 LAST PATH I120
J 0
(-6477 2100);
DISPLAY 0.872340 (-6477 2100);
PAINT GREEN (-6477 2100);
DISPLAY INVISIBLE (-6477 2100);
FORCEADD TAP..1
(-6275 2050);
FORCEPROP 3 LASTPIN (-6325 2050) SIG_NAME P5E_CPU1_P3_TX_BUF_C_DN<8>
J 0
(-6315 2060);
DISPLAY 0.659574 (-6315 2060);
PAINT MONO (-6315 2060);
DISPLAY INVISIBLE (-6315 2060);
FORCEPROP 1 LASTPIN (-6325 2050) BN 8
J 0
(-6337 2058);
DISPLAY 0.680851 (-6337 2058);
PAINT GREEN (-6337 2058);
FORCEPROP 2 LAST CDS_LIB standard
J 0
(-6275 2050);
DISPLAY INVISIBLE (-6275 2050);
FORCEPROP 1 LAST BODY_TYPE PLUMBING
J 0
(-6275 2100);
DISPLAY 0.872340 (-6275 2100);
PAINT GREEN (-6275 2100);
DISPLAY INVISIBLE (-6275 2100);
FORCEPROP 1 LAST HDL_TAP TRUE
J 0
(-5950 1925);
DISPLAY 0.872340 (-5950 1925);
DISPLAY INVISIBLE (-5950 1925);
FORCEPROP 1 LAST PATH I121
J 0
(-6277 2050);
DISPLAY 0.872340 (-6277 2050);
PAINT GREEN (-6277 2050);
DISPLAY INVISIBLE (-6277 2050);
FORCEADD TAP..1
(-1875 3300);
FORCEPROP 3 LASTPIN (-1925 3300) SIG_NAME P5E_CPU1_P3_TX_BUF_DP<0>
J 0
(-1915 3310);
DISPLAY 0.659574 (-1915 3310);
PAINT MONO (-1915 3310);
DISPLAY INVISIBLE (-1915 3310);
FORCEPROP 1 LASTPIN (-1925 3300) BN 0
J 0
(-1937 3308);
DISPLAY 0.680851 (-1937 3308);
PAINT GREEN (-1937 3308);
FORCEPROP 2 LAST CDS_LIB standard
J 0
(-1875 3300);
DISPLAY INVISIBLE (-1875 3300);
FORCEPROP 1 LAST BODY_TYPE PLUMBING
J 0
(-1875 3350);
DISPLAY 0.872340 (-1875 3350);
PAINT GREEN (-1875 3350);
DISPLAY INVISIBLE (-1875 3350);
FORCEPROP 1 LAST HDL_TAP TRUE
J 0
(-1550 3175);
DISPLAY 0.872340 (-1550 3175);
DISPLAY INVISIBLE (-1550 3175);
FORCEPROP 1 LAST PATH I122
J 0
(-1877 3300);
DISPLAY 0.872340 (-1877 3300);
PAINT GREEN (-1877 3300);
DISPLAY INVISIBLE (-1877 3300);
FORCEADD TAP..1
(-1675 3200);
FORCEPROP 3 LASTPIN (-1725 3200) SIG_NAME P5E_CPU1_P3_TX_BUF_DN<0>
J 0
(-1715 3210);
DISPLAY 0.659574 (-1715 3210);
PAINT MONO (-1715 3210);
DISPLAY INVISIBLE (-1715 3210);
FORCEPROP 1 LASTPIN (-1725 3200) BN 0
J 0
(-1737 3208);
DISPLAY 0.680851 (-1737 3208);
PAINT GREEN (-1737 3208);
FORCEPROP 2 LAST CDS_LIB standard
J 0
(-1675 3200);
DISPLAY INVISIBLE (-1675 3200);
FORCEPROP 1 LAST BODY_TYPE PLUMBING
J 0
(-1675 3250);
DISPLAY 0.872340 (-1675 3250);
PAINT GREEN (-1675 3250);
DISPLAY INVISIBLE (-1675 3250);
FORCEPROP 1 LAST HDL_TAP TRUE
J 0
(-1350 3075);
DISPLAY 0.872340 (-1350 3075);
DISPLAY INVISIBLE (-1350 3075);
FORCEPROP 1 LAST PATH I123
J 0
(-1677 3200);
DISPLAY 0.872340 (-1677 3200);
PAINT GREEN (-1677 3200);
DISPLAY INVISIBLE (-1677 3200);
FORCEADD TAP..1
(-1875 3650);
FORCEPROP 3 LASTPIN (-1925 3650) SIG_NAME P5E_CPU1_P3_TX_BUF_DP<1>
J 0
(-1915 3660);
DISPLAY 0.659574 (-1915 3660);
PAINT MONO (-1915 3660);
DISPLAY INVISIBLE (-1915 3660);
FORCEPROP 1 LASTPIN (-1925 3650) BN 1
J 0
(-1937 3658);
DISPLAY 0.680851 (-1937 3658);
PAINT GREEN (-1937 3658);
FORCEPROP 2 LAST CDS_LIB standard
J 0
(-1875 3650);
DISPLAY INVISIBLE (-1875 3650);
FORCEPROP 1 LAST BODY_TYPE PLUMBING
J 0
(-1875 3700);
DISPLAY 0.872340 (-1875 3700);
PAINT GREEN (-1875 3700);
DISPLAY INVISIBLE (-1875 3700);
FORCEPROP 1 LAST HDL_TAP TRUE
J 0
(-1550 3525);
DISPLAY 0.872340 (-1550 3525);
DISPLAY INVISIBLE (-1550 3525);
FORCEPROP 1 LAST PATH I124
J 0
(-1877 3650);
DISPLAY 0.872340 (-1877 3650);
PAINT GREEN (-1877 3650);
DISPLAY INVISIBLE (-1877 3650);
FORCEADD TAP..1
(-1675 3550);
FORCEPROP 3 LASTPIN (-1725 3550) SIG_NAME P5E_CPU1_P3_TX_BUF_DN<1>
J 0
(-1715 3560);
DISPLAY 0.659574 (-1715 3560);
PAINT MONO (-1715 3560);
DISPLAY INVISIBLE (-1715 3560);
FORCEPROP 1 LASTPIN (-1725 3550) BN 1
J 0
(-1737 3558);
DISPLAY 0.680851 (-1737 3558);
PAINT GREEN (-1737 3558);
FORCEPROP 2 LAST CDS_LIB standard
J 0
(-1675 3550);
DISPLAY INVISIBLE (-1675 3550);
FORCEPROP 1 LAST BODY_TYPE PLUMBING
J 0
(-1675 3600);
DISPLAY 0.872340 (-1675 3600);
PAINT GREEN (-1675 3600);
DISPLAY INVISIBLE (-1675 3600);
FORCEPROP 1 LAST HDL_TAP TRUE
J 0
(-1350 3425);
DISPLAY 0.872340 (-1350 3425);
DISPLAY INVISIBLE (-1350 3425);
FORCEPROP 1 LAST PATH I125
J 0
(-1677 3550);
DISPLAY 0.872340 (-1677 3550);
PAINT GREEN (-1677 3550);
DISPLAY INVISIBLE (-1677 3550);
FORCEADD TAP..1
(-1675 3900);
FORCEPROP 3 LASTPIN (-1725 3900) SIG_NAME P5E_CPU1_P3_TX_BUF_DN<2>
J 0
(-1715 3910);
DISPLAY 0.659574 (-1715 3910);
PAINT MONO (-1715 3910);
DISPLAY INVISIBLE (-1715 3910);
FORCEPROP 1 LASTPIN (-1725 3900) BN 2
J 0
(-1737 3908);
DISPLAY 0.680851 (-1737 3908);
PAINT GREEN (-1737 3908);
FORCEPROP 2 LAST CDS_LIB standard
J 0
(-1675 3900);
DISPLAY INVISIBLE (-1675 3900);
FORCEPROP 1 LAST BODY_TYPE PLUMBING
J 0
(-1675 3950);
DISPLAY 0.872340 (-1675 3950);
PAINT GREEN (-1675 3950);
DISPLAY INVISIBLE (-1675 3950);
FORCEPROP 1 LAST HDL_TAP TRUE
J 0
(-1350 3775);
DISPLAY 0.872340 (-1350 3775);
DISPLAY INVISIBLE (-1350 3775);
FORCEPROP 1 LAST PATH I126
J 0
(-1677 3900);
DISPLAY 0.872340 (-1677 3900);
PAINT GREEN (-1677 3900);
DISPLAY INVISIBLE (-1677 3900);
FORCEADD OFFPAGE..2
(-5275 2075);
FORCEPROP 2 LAST $XR0 119 
J 0
(-5086 2075);
DISPLAY 0.638298 (-5086 2075);
PAINT MONO (-5086 2075);
FORCEPROP 2 LAST CDS_LIB standard
J 0
(-5275 2075);
DISPLAY INVISIBLE (-5275 2075);
FORCEPROP 1 LAST OFFPAGE TRUE
J 0
(-4950 1950);
DISPLAY 0.872340 (-4950 1950);
DISPLAY INVISIBLE (-4950 1950);
FORCEPROP 1 LAST COMMENT_BODY TRUE
J 0
(-5320 1980);
DISPLAY 0.872340 (-5320 1980);
PAINT GREEN (-5320 1980);
DISPLAY INVISIBLE (-5320 1980);
FORCEPROP 2 LAST PATH I127
J 0
(-5075 2125);
DISPLAY 0.680851 (-5075 2125);
DISPLAY INVISIBLE (-5075 2125);
FORCEADD OFFPAGE..2
(-5275 2125);
FORCEPROP 2 LAST $XR0 119 
J 0
(-5086 2125);
DISPLAY 0.638298 (-5086 2125);
PAINT MONO (-5086 2125);
FORCEPROP 2 LAST CDS_LIB standard
J 0
(-5275 2125);
DISPLAY INVISIBLE (-5275 2125);
FORCEPROP 1 LAST OFFPAGE TRUE
J 0
(-4950 2000);
DISPLAY 0.872340 (-4950 2000);
DISPLAY INVISIBLE (-4950 2000);
FORCEPROP 1 LAST COMMENT_BODY TRUE
J 0
(-5320 2030);
DISPLAY 0.872340 (-5320 2030);
PAINT GREEN (-5320 2030);
DISPLAY INVISIBLE (-5320 2030);
FORCEPROP 2 LAST PATH I128
J 0
(-5075 2175);
DISPLAY 0.680851 (-5075 2175);
DISPLAY INVISIBLE (-5075 2175);
FORCEADD TAP..1
(-1875 4000);
FORCEPROP 3 LASTPIN (-1925 4000) SIG_NAME P5E_CPU1_P3_TX_BUF_DP<2>
J 0
(-1915 4010);
DISPLAY 0.659574 (-1915 4010);
PAINT MONO (-1915 4010);
DISPLAY INVISIBLE (-1915 4010);
FORCEPROP 1 LASTPIN (-1925 4000) BN 2
J 0
(-1937 4008);
DISPLAY 0.680851 (-1937 4008);
PAINT GREEN (-1937 4008);
FORCEPROP 2 LAST CDS_LIB standard
J 0
(-1875 4000);
DISPLAY INVISIBLE (-1875 4000);
FORCEPROP 1 LAST BODY_TYPE PLUMBING
J 0
(-1875 4050);
DISPLAY 0.872340 (-1875 4050);
PAINT GREEN (-1875 4050);
DISPLAY INVISIBLE (-1875 4050);
FORCEPROP 1 LAST HDL_TAP TRUE
J 0
(-1550 3875);
DISPLAY 0.872340 (-1550 3875);
DISPLAY INVISIBLE (-1550 3875);
FORCEPROP 1 LAST PATH I129
J 0
(-1877 4000);
DISPLAY 0.872340 (-1877 4000);
PAINT GREEN (-1877 4000);
DISPLAY INVISIBLE (-1877 4000);
FORCEADD TAP..1
R 2
(-3175 1425);
FORCEPROP 3 LASTPIN (-3125 1425) SIG_NAME P5E_CPU1_P3_TX_BUF_DP<4>
J 0
(-3115 1435);
DISPLAY 0.659574 (-3115 1435);
PAINT MONO (-3115 1435);
DISPLAY INVISIBLE (-3115 1435);
FORCEPROP 1 LASTPIN (-3125 1425) BN 4
J 2
(-3113 1433);
DISPLAY 0.680851 (-3113 1433);
PAINT GREEN (-3113 1433);
FORCEPROP 2 LAST CDS_LIB standard
J 0
(-3175 1425);
DISPLAY INVISIBLE (-3175 1425);
FORCEPROP 1 LAST BODY_TYPE PLUMBING
J 2
(-3175 1475);
DISPLAY 0.872340 (-3175 1475);
PAINT GREEN (-3175 1475);
DISPLAY INVISIBLE (-3175 1475);
FORCEPROP 1 LAST HDL_TAP TRUE
J 2
(-3500 1300);
DISPLAY 0.872340 (-3500 1300);
DISPLAY INVISIBLE (-3500 1300);
FORCEPROP 1 LAST PATH I13
J 2
(-3173 1425);
DISPLAY 0.872340 (-3173 1425);
PAINT GREEN (-3173 1425);
DISPLAY INVISIBLE (-3173 1425);
FORCEADD TAP..1
(-1875 4350);
FORCEPROP 3 LASTPIN (-1925 4350) SIG_NAME P5E_CPU1_P3_TX_BUF_DP<3>
J 0
(-1915 4360);
DISPLAY 0.659574 (-1915 4360);
PAINT MONO (-1915 4360);
DISPLAY INVISIBLE (-1915 4360);
FORCEPROP 1 LASTPIN (-1925 4350) BN 3
J 0
(-1937 4358);
DISPLAY 0.680851 (-1937 4358);
PAINT GREEN (-1937 4358);
FORCEPROP 2 LAST CDS_LIB standard
J 0
(-1875 4350);
DISPLAY INVISIBLE (-1875 4350);
FORCEPROP 1 LAST BODY_TYPE PLUMBING
J 0
(-1875 4400);
DISPLAY 0.872340 (-1875 4400);
PAINT GREEN (-1875 4400);
DISPLAY INVISIBLE (-1875 4400);
FORCEPROP 1 LAST HDL_TAP TRUE
J 0
(-1550 4225);
DISPLAY 0.872340 (-1550 4225);
DISPLAY INVISIBLE (-1550 4225);
FORCEPROP 1 LAST PATH I130
J 0
(-1877 4350);
DISPLAY 0.872340 (-1877 4350);
PAINT GREEN (-1877 4350);
DISPLAY INVISIBLE (-1877 4350);
FORCEADD TAP..1
(-1675 4250);
FORCEPROP 3 LASTPIN (-1725 4250) SIG_NAME P5E_CPU1_P3_TX_BUF_DN<3>
J 0
(-1715 4260);
DISPLAY 0.659574 (-1715 4260);
PAINT MONO (-1715 4260);
DISPLAY INVISIBLE (-1715 4260);
FORCEPROP 1 LASTPIN (-1725 4250) BN 3
J 0
(-1737 4258);
DISPLAY 0.680851 (-1737 4258);
PAINT GREEN (-1737 4258);
FORCEPROP 2 LAST CDS_LIB standard
J 0
(-1675 4250);
DISPLAY INVISIBLE (-1675 4250);
FORCEPROP 1 LAST BODY_TYPE PLUMBING
J 0
(-1675 4300);
DISPLAY 0.872340 (-1675 4300);
PAINT GREEN (-1675 4300);
DISPLAY INVISIBLE (-1675 4300);
FORCEPROP 1 LAST HDL_TAP TRUE
J 0
(-1350 4125);
DISPLAY 0.872340 (-1350 4125);
DISPLAY INVISIBLE (-1350 4125);
FORCEPROP 1 LAST PATH I131
J 0
(-1677 4250);
DISPLAY 0.872340 (-1677 4250);
PAINT GREEN (-1677 4250);
DISPLAY INVISIBLE (-1677 4250);
FORCEADD TAP..1
(-1675 4600);
FORCEPROP 3 LASTPIN (-1725 4600) SIG_NAME P5E_CPU1_P3_TX_BUF_DN<4>
J 0
(-1715 4610);
DISPLAY 0.659574 (-1715 4610);
PAINT MONO (-1715 4610);
DISPLAY INVISIBLE (-1715 4610);
FORCEPROP 1 LASTPIN (-1725 4600) BN 4
J 0
(-1737 4608);
DISPLAY 0.680851 (-1737 4608);
PAINT GREEN (-1737 4608);
FORCEPROP 2 LAST CDS_LIB standard
J 0
(-1675 4600);
DISPLAY INVISIBLE (-1675 4600);
FORCEPROP 1 LAST BODY_TYPE PLUMBING
J 0
(-1675 4650);
DISPLAY 0.872340 (-1675 4650);
PAINT GREEN (-1675 4650);
DISPLAY INVISIBLE (-1675 4650);
FORCEPROP 1 LAST HDL_TAP TRUE
J 0
(-1350 4475);
DISPLAY 0.872340 (-1350 4475);
DISPLAY INVISIBLE (-1350 4475);
FORCEPROP 1 LAST PATH I132
J 0
(-1677 4600);
DISPLAY 0.872340 (-1677 4600);
PAINT GREEN (-1677 4600);
DISPLAY INVISIBLE (-1677 4600);
FORCEADD TAP..1
(-1675 4950);
FORCEPROP 3 LASTPIN (-1725 4950) SIG_NAME P5E_CPU1_P3_TX_BUF_DN<5>
J 0
(-1715 4960);
DISPLAY 0.659574 (-1715 4960);
PAINT MONO (-1715 4960);
DISPLAY INVISIBLE (-1715 4960);
FORCEPROP 1 LASTPIN (-1725 4950) BN 5
J 0
(-1737 4958);
DISPLAY 0.680851 (-1737 4958);
PAINT GREEN (-1737 4958);
FORCEPROP 2 LAST CDS_LIB standard
J 0
(-1675 4950);
DISPLAY INVISIBLE (-1675 4950);
FORCEPROP 1 LAST BODY_TYPE PLUMBING
J 0
(-1675 5000);
DISPLAY 0.872340 (-1675 5000);
PAINT GREEN (-1675 5000);
DISPLAY INVISIBLE (-1675 5000);
FORCEPROP 1 LAST HDL_TAP TRUE
J 0
(-1350 4825);
DISPLAY 0.872340 (-1350 4825);
DISPLAY INVISIBLE (-1350 4825);
FORCEPROP 1 LAST PATH I133
J 0
(-1677 4950);
DISPLAY 0.872340 (-1677 4950);
PAINT GREEN (-1677 4950);
DISPLAY INVISIBLE (-1677 4950);
FORCEADD TAP..1
(-1875 5050);
FORCEPROP 3 LASTPIN (-1925 5050) SIG_NAME P5E_CPU1_P3_TX_BUF_DP<5>
J 0
(-1915 5060);
DISPLAY 0.659574 (-1915 5060);
PAINT MONO (-1915 5060);
DISPLAY INVISIBLE (-1915 5060);
FORCEPROP 1 LASTPIN (-1925 5050) BN 5
J 0
(-1937 5058);
DISPLAY 0.680851 (-1937 5058);
PAINT GREEN (-1937 5058);
FORCEPROP 2 LAST CDS_LIB standard
J 0
(-1875 5050);
DISPLAY INVISIBLE (-1875 5050);
FORCEPROP 1 LAST BODY_TYPE PLUMBING
J 0
(-1875 5100);
DISPLAY 0.872340 (-1875 5100);
PAINT GREEN (-1875 5100);
DISPLAY INVISIBLE (-1875 5100);
FORCEPROP 1 LAST HDL_TAP TRUE
J 0
(-1550 4925);
DISPLAY 0.872340 (-1550 4925);
DISPLAY INVISIBLE (-1550 4925);
FORCEPROP 1 LAST PATH I134
J 0
(-1877 5050);
DISPLAY 0.872340 (-1877 5050);
PAINT GREEN (-1877 5050);
DISPLAY INVISIBLE (-1877 5050);
FORCEADD TAP..1
(-1875 5400);
FORCEPROP 3 LASTPIN (-1925 5400) SIG_NAME P5E_CPU1_P3_TX_BUF_DP<6>
J 0
(-1915 5410);
DISPLAY 0.659574 (-1915 5410);
PAINT MONO (-1915 5410);
DISPLAY INVISIBLE (-1915 5410);
FORCEPROP 1 LASTPIN (-1925 5400) BN 6
J 0
(-1937 5408);
DISPLAY 0.680851 (-1937 5408);
PAINT GREEN (-1937 5408);
FORCEPROP 2 LAST CDS_LIB standard
J 0
(-1875 5400);
DISPLAY INVISIBLE (-1875 5400);
FORCEPROP 1 LAST BODY_TYPE PLUMBING
J 0
(-1875 5450);
DISPLAY 0.872340 (-1875 5450);
PAINT GREEN (-1875 5450);
DISPLAY INVISIBLE (-1875 5450);
FORCEPROP 1 LAST HDL_TAP TRUE
J 0
(-1550 5275);
DISPLAY 0.872340 (-1550 5275);
DISPLAY INVISIBLE (-1550 5275);
FORCEPROP 1 LAST PATH I135
J 0
(-1877 5400);
DISPLAY 0.872340 (-1877 5400);
PAINT GREEN (-1877 5400);
DISPLAY INVISIBLE (-1877 5400);
FORCEADD TAP..1
(-1675 5300);
FORCEPROP 3 LASTPIN (-1725 5300) SIG_NAME P5E_CPU1_P3_TX_BUF_DN<6>
J 0
(-1715 5310);
DISPLAY 0.659574 (-1715 5310);
PAINT MONO (-1715 5310);
DISPLAY INVISIBLE (-1715 5310);
FORCEPROP 1 LASTPIN (-1725 5300) BN 6
J 0
(-1737 5308);
DISPLAY 0.680851 (-1737 5308);
PAINT GREEN (-1737 5308);
FORCEPROP 2 LAST CDS_LIB standard
J 0
(-1675 5300);
DISPLAY INVISIBLE (-1675 5300);
FORCEPROP 1 LAST BODY_TYPE PLUMBING
J 0
(-1675 5350);
DISPLAY 0.872340 (-1675 5350);
PAINT GREEN (-1675 5350);
DISPLAY INVISIBLE (-1675 5350);
FORCEPROP 1 LAST HDL_TAP TRUE
J 0
(-1350 5175);
DISPLAY 0.872340 (-1350 5175);
DISPLAY INVISIBLE (-1350 5175);
FORCEPROP 1 LAST PATH I136
J 0
(-1677 5300);
DISPLAY 0.872340 (-1677 5300);
PAINT GREEN (-1677 5300);
DISPLAY INVISIBLE (-1677 5300);
FORCEADD TAP..1
(-1875 5750);
FORCEPROP 3 LASTPIN (-1925 5750) SIG_NAME P5E_CPU1_P3_TX_BUF_DP<7>
J 0
(-1915 5760);
DISPLAY 0.659574 (-1915 5760);
PAINT MONO (-1915 5760);
DISPLAY INVISIBLE (-1915 5760);
FORCEPROP 1 LASTPIN (-1925 5750) BN 7
J 0
(-1937 5758);
DISPLAY 0.680851 (-1937 5758);
PAINT GREEN (-1937 5758);
FORCEPROP 2 LAST CDS_LIB standard
J 0
(-1875 5750);
DISPLAY INVISIBLE (-1875 5750);
FORCEPROP 1 LAST BODY_TYPE PLUMBING
J 0
(-1875 5800);
DISPLAY 0.872340 (-1875 5800);
PAINT GREEN (-1875 5800);
DISPLAY INVISIBLE (-1875 5800);
FORCEPROP 1 LAST HDL_TAP TRUE
J 0
(-1550 5625);
DISPLAY 0.872340 (-1550 5625);
DISPLAY INVISIBLE (-1550 5625);
FORCEPROP 1 LAST PATH I137
J 0
(-1877 5750);
DISPLAY 0.872340 (-1877 5750);
PAINT GREEN (-1877 5750);
DISPLAY INVISIBLE (-1877 5750);
FORCEADD TAP..1
(-1675 5650);
FORCEPROP 3 LASTPIN (-1725 5650) SIG_NAME P5E_CPU1_P3_TX_BUF_DN<7>
J 0
(-1715 5660);
DISPLAY 0.659574 (-1715 5660);
PAINT MONO (-1715 5660);
DISPLAY INVISIBLE (-1715 5660);
FORCEPROP 1 LASTPIN (-1725 5650) BN 7
J 0
(-1737 5658);
DISPLAY 0.680851 (-1737 5658);
PAINT GREEN (-1737 5658);
FORCEPROP 2 LAST CDS_LIB standard
J 0
(-1675 5650);
DISPLAY INVISIBLE (-1675 5650);
FORCEPROP 1 LAST BODY_TYPE PLUMBING
J 0
(-1675 5700);
DISPLAY 0.872340 (-1675 5700);
PAINT GREEN (-1675 5700);
DISPLAY INVISIBLE (-1675 5700);
FORCEPROP 1 LAST HDL_TAP TRUE
J 0
(-1350 5525);
DISPLAY 0.872340 (-1350 5525);
DISPLAY INVISIBLE (-1350 5525);
FORCEPROP 1 LAST PATH I138
J 0
(-1677 5650);
DISPLAY 0.872340 (-1677 5650);
PAINT GREEN (-1677 5650);
DISPLAY INVISIBLE (-1677 5650);
FORCEADD OFFPAGE..5
R 2
(-700 5675);
FORCEPROP 2 LAST $XR0 353 
J 0
(-511 5675);
DISPLAY 0.638298 (-511 5675);
PAINT MONO (-511 5675);
FORCEPROP 2 LAST CDS_LIB standard
J 0
(-700 5675);
DISPLAY INVISIBLE (-700 5675);
FORCEPROP 1 LAST OFFPAGE TRUE
J 2
(-1025 5550);
DISPLAY 0.872340 (-1025 5550);
PAINT GREEN (-1025 5550);
DISPLAY INVISIBLE (-1025 5550);
FORCEPROP 1 LAST COMMENT_BODY TRUE
J 2
(-800 5600);
DISPLAY 0.872340 (-800 5600);
PAINT GREEN (-800 5600);
DISPLAY INVISIBLE (-800 5600);
FORCEPROP 2 LAST PATH I139
J 0
(-525 5750);
DISPLAY 0.680851 (-525 5750);
DISPLAY INVISIBLE (-525 5750);
FORCEADD TAP..1
R 2
(-3175 1625);
FORCEPROP 3 LASTPIN (-3125 1625) SIG_NAME P5E_CPU1_P3_TX_BUF_DP<3>
J 0
(-3115 1635);
DISPLAY 0.659574 (-3115 1635);
PAINT MONO (-3115 1635);
DISPLAY INVISIBLE (-3115 1635);
FORCEPROP 1 LASTPIN (-3125 1625) BN 3
J 2
(-3113 1633);
DISPLAY 0.680851 (-3113 1633);
PAINT GREEN (-3113 1633);
FORCEPROP 2 LAST CDS_LIB standard
J 0
(-3175 1625);
DISPLAY INVISIBLE (-3175 1625);
FORCEPROP 1 LAST BODY_TYPE PLUMBING
J 2
(-3175 1675);
DISPLAY 0.872340 (-3175 1675);
PAINT GREEN (-3175 1675);
DISPLAY INVISIBLE (-3175 1675);
FORCEPROP 1 LAST HDL_TAP TRUE
J 2
(-3500 1500);
DISPLAY 0.872340 (-3500 1500);
DISPLAY INVISIBLE (-3500 1500);
FORCEPROP 1 LAST PATH I14
J 2
(-3173 1625);
DISPLAY 0.872340 (-3173 1625);
PAINT GREEN (-3173 1625);
DISPLAY INVISIBLE (-3173 1625);
FORCEADD OFFPAGE..5
R 2
(-675 5775);
FORCEPROP 2 LAST $XR0 353 
J 0
(-486 5775);
DISPLAY 0.638298 (-486 5775);
PAINT MONO (-486 5775);
FORCEPROP 2 LAST CDS_LIB standard
J 0
(-675 5775);
DISPLAY INVISIBLE (-675 5775);
FORCEPROP 1 LAST OFFPAGE TRUE
J 2
(-1000 5650);
DISPLAY 0.872340 (-1000 5650);
PAINT GREEN (-1000 5650);
DISPLAY INVISIBLE (-1000 5650);
FORCEPROP 1 LAST COMMENT_BODY TRUE
J 2
(-775 5700);
DISPLAY 0.872340 (-775 5700);
PAINT GREEN (-775 5700);
DISPLAY INVISIBLE (-775 5700);
FORCEPROP 2 LAST PATH I140
J 0
(-500 5850);
DISPLAY 0.680851 (-500 5850);
DISPLAY INVISIBLE (-500 5850);
FORCEADD TAP..1
(-1875 4700);
FORCEPROP 3 LASTPIN (-1925 4700) SIG_NAME P5E_CPU1_P3_TX_BUF_DP<4>
J 0
(-1915 4710);
DISPLAY 0.659574 (-1915 4710);
PAINT MONO (-1915 4710);
DISPLAY INVISIBLE (-1915 4710);
FORCEPROP 1 LASTPIN (-1925 4700) BN 4
J 0
(-1937 4708);
DISPLAY 0.680851 (-1937 4708);
PAINT GREEN (-1937 4708);
FORCEPROP 2 LAST CDS_LIB standard
J 0
(-1875 4700);
DISPLAY INVISIBLE (-1875 4700);
FORCEPROP 1 LAST BODY_TYPE PLUMBING
J 0
(-1875 4750);
DISPLAY 0.872340 (-1875 4750);
PAINT GREEN (-1875 4750);
DISPLAY INVISIBLE (-1875 4750);
FORCEPROP 1 LAST HDL_TAP TRUE
J 0
(-1550 4575);
DISPLAY 0.872340 (-1550 4575);
DISPLAY INVISIBLE (-1550 4575);
FORCEPROP 1 LAST PATH I141
J 0
(-1877 4700);
DISPLAY 0.872340 (-1877 4700);
PAINT GREEN (-1877 4700);
DISPLAY INVISIBLE (-1877 4700);
FORCEADD PT5161LRS..11
(-2600 4500);
FORCEPROP 1 LAST LOCATION U6017
J 0
(-2950 6125);
DISPLAY 0.723404 (-2950 6125);
PAINT GREEN (-2950 6125);
FORCEPROP 0 LAST $SEC 11
J 0
(-2950 6275);
DISPLAY 0.680851 (-2950 6275);
PAINT MONO (-2950 6275);
DISPLAY INVISIBLE (-2950 6275);
FORCEPROP 0 LAST CDS_SEC 11
J 0
(-2950 6275);
DISPLAY 0.680851 (-2950 6275);
DISPLAY INVISIBLE (-2950 6275);
FORCEPROP 0 LASTPIN (-2150 5650) $PN CK10
J 0
(-2140 5660);
DISPLAY 0.680851 (-2140 5660);
PAINT MONO (-2140 5660);
FORCEPROP 0 LASTPIN (-2150 5300) $PN CU10
J 0
(-2140 5310);
DISPLAY 0.680851 (-2140 5310);
PAINT MONO (-2140 5310);
FORCEPROP 0 LASTPIN (-2150 4950) $PN DD10
J 0
(-2140 4960);
DISPLAY 0.680851 (-2140 4960);
PAINT MONO (-2140 4960);
FORCEPROP 0 LASTPIN (-2150 4600) $PN DL10
J 0
(-2140 4610);
DISPLAY 0.680851 (-2140 4610);
PAINT MONO (-2140 4610);
FORCEPROP 0 LASTPIN (-2150 4250) $PN DV10
J 0
(-2140 4260);
DISPLAY 0.680851 (-2140 4260);
PAINT MONO (-2140 4260);
FORCEPROP 0 LASTPIN (-2150 3900) $PN EE10
J 0
(-2140 3910);
DISPLAY 0.680851 (-2140 3910);
PAINT MONO (-2140 3910);
FORCEPROP 0 LASTPIN (-2150 3550) $PN EM10
J 0
(-2140 3560);
DISPLAY 0.680851 (-2140 3560);
PAINT MONO (-2140 3560);
FORCEPROP 0 LASTPIN (-2150 3200) $PN EW10
J 0
(-2140 3210);
DISPLAY 0.680851 (-2140 3210);
PAINT MONO (-2140 3210);
FORCEPROP 0 LASTPIN (-2150 5750) $PN CH7
J 0
(-2140 5760);
DISPLAY 0.680851 (-2140 5760);
PAINT MONO (-2140 5760);
FORCEPROP 0 LASTPIN (-2150 5400) $PN CR7
J 0
(-2140 5410);
DISPLAY 0.680851 (-2140 5410);
PAINT MONO (-2140 5410);
FORCEPROP 0 LASTPIN (-2150 5050) $PN DB7
J 0
(-2140 5060);
DISPLAY 0.680851 (-2140 5060);
PAINT MONO (-2140 5060);
FORCEPROP 0 LASTPIN (-2150 4700) $PN DJ7
J 0
(-2140 4710);
DISPLAY 0.680851 (-2140 4710);
PAINT MONO (-2140 4710);
FORCEPROP 0 LASTPIN (-2150 4350) $PN DT7
J 0
(-2140 4360);
DISPLAY 0.680851 (-2140 4360);
PAINT MONO (-2140 4360);
FORCEPROP 0 LASTPIN (-2150 4000) $PN EC7
J 0
(-2140 4010);
DISPLAY 0.680851 (-2140 4010);
PAINT MONO (-2140 4010);
FORCEPROP 0 LASTPIN (-2150 3650) $PN EK7
J 0
(-2140 3660);
DISPLAY 0.680851 (-2140 3660);
PAINT MONO (-2140 3660);
FORCEPROP 0 LASTPIN (-2150 3300) $PN EU7
J 0
(-2140 3310);
DISPLAY 0.680851 (-2140 3310);
PAINT MONO (-2140 3310);
FORCEPROP 1 LAST MATERIAL IC
J 0
(-2950 5975);
DISPLAY 0.723404 (-2950 5975);
PAINT GREEN (-2950 5975);
FORCEPROP 2 LAST VALUE PT5161LRS
J 0
(-2950 6175);
DISPLAY 0.680851 (-2950 6175);
FORCEPROP 2 LAST PART_TYPE SMLF
J 0
(-2950 6225);
DISPLAY 0.680851 (-2950 6225);
FORCEPROP 1 LAST NEEDS_NO_SIZE TRUE
J 0
(-2600 4500);
DISPLAY 0.723404 (-2600 4500);
PAINT GREEN (-2600 4500);
DISPLAY INVISIBLE (-2600 4500);
FORCEPROP 1 LAST CDS_LMAN_SYM_OUTLINE -350,1450,300,-1400
J 0
(-2600 4500);
DISPLAY 0.468085 (-2600 4500);
PAINT GREEN (-2600 4500);
DISPLAY INVISIBLE (-2600 4500);
FORCEPROP 2 LAST CDS_LIB pure_quanta
J 0
(-2600 4500);
DISPLAY INVISIBLE (-2600 4500);
FORCEPROP 1 LAST PATH I142
J 0
(-2600 4500);
DISPLAY 0.723404 (-2600 4500);
PAINT GREEN (-2600 4500);
DISPLAY INVISIBLE (-2600 4500);
FORCEPROP 1 LAST PART_NUMBER AJ051610U03
J 0
(-2950 6050);
DISPLAY 0.723404 (-2950 6050);
PAINT GREEN (-2950 6050);
DISPLAY INVISIBLE (-2950 6050);
FORCEADD TAP..1
R 2
(-3175 1825);
FORCEPROP 3 LASTPIN (-3125 1825) SIG_NAME P5E_CPU1_P3_TX_BUF_DP<2>
J 0
(-3115 1835);
DISPLAY 0.659574 (-3115 1835);
PAINT MONO (-3115 1835);
DISPLAY INVISIBLE (-3115 1835);
FORCEPROP 1 LASTPIN (-3125 1825) BN 2
J 2
(-3113 1833);
DISPLAY 0.680851 (-3113 1833);
PAINT GREEN (-3113 1833);
FORCEPROP 2 LAST CDS_LIB standard
J 0
(-3175 1825);
DISPLAY INVISIBLE (-3175 1825);
FORCEPROP 1 LAST BODY_TYPE PLUMBING
J 2
(-3175 1875);
DISPLAY 0.872340 (-3175 1875);
PAINT GREEN (-3175 1875);
DISPLAY INVISIBLE (-3175 1875);
FORCEPROP 1 LAST HDL_TAP TRUE
J 2
(-3500 1700);
DISPLAY 0.872340 (-3500 1700);
DISPLAY INVISIBLE (-3500 1700);
FORCEPROP 1 LAST PATH I15
J 2
(-3173 1825);
DISPLAY 0.872340 (-3173 1825);
PAINT GREEN (-3173 1825);
DISPLAY INVISIBLE (-3173 1825);
FORCEADD Q_CAP_DIFFBUS..2
R 2
(-2450 975);
FORCEPROP 1 LAST LOCATION C6738
J 2
(-2175 975);
DISPLAY 0.723404 (-2175 975);
PAINT GREEN (-2175 975);
FORCEPROP 2 LAST $SEC 1
J 2
(-2275 1050);
DISPLAY 0.680851 (-2275 1050);
PAINT MONO (-2275 1050);
DISPLAY INVISIBLE (-2275 1050);
FORCEPROP 2 LAST CDS_SEC 1
J 2
(-2275 1050);
DISPLAY 0.680851 (-2275 1050);
DISPLAY INVISIBLE (-2275 1050);
FORCEPROP 2 LASTPIN (-2375 975) $PN 1
J 0
(-2365 985);
DISPLAY 0.808511 (-2365 985);
FORCEPROP 2 LASTPIN (-2525 975) $PN 2
J 2
(-2535 985);
DISPLAY 0.808511 (-2535 985);
FORCEPROP 2 LAST VALUE DIFF BUS_0.22UF
J 2
(-2600 975);
DISPLAY 0.553191 (-2600 975);
FORCEPROP 1 LAST CDS_LMAN_SYM_OUTLINE -25,50,25,-50
J 2
(-2450 975);
DISPLAY 0.468085 (-2450 975);
PAINT GREEN (-2450 975);
DISPLAY INVISIBLE (-2450 975);
FORCEPROP 2 LAST CDS_LIB pure_quanta
J 2
(-2450 975);
DISPLAY INVISIBLE (-2450 975);
FORCEPROP 1 LAST PIN_NAMES_ROTATE TRUE
J 2
(-2450 975);
DISPLAY 0.489362 (-2450 975);
PAINT GREEN (-2450 975);
DISPLAY INVISIBLE (-2450 975);
FORCEPROP 2 LAST VOLTAGE 6.3V
J 2
(-2800 1025);
DISPLAY 0.553191 (-2800 1025);
DISPLAY INVISIBLE (-2800 1025);
FORCEPROP 1 LAST MATERIAL X6S
J 2
(-2441 1054);
DISPLAY 0.574468 (-2441 1054);
PAINT GREEN (-2441 1054);
DISPLAY INVISIBLE (-2441 1054);
FORCEPROP 2 LAST PACK_TYPE C0201
J 2
(-2625 1025);
DISPLAY 0.553191 (-2625 1025);
DISPLAY INVISIBLE (-2625 1025);
FORCEPROP 2 LAST TOLERANCE 20%
J 2
(-2525 1025);
DISPLAY 0.553191 (-2525 1025);
DISPLAY INVISIBLE (-2525 1025);
FORCEPROP 1 LAST PATH I16
J 2
(-2450 975);
DISPLAY 0.723404 (-2450 975);
DISPLAY INVISIBLE (-2450 975);
FORCEPROP 1 LAST PART_NUMBER SP_CH4221MEE01
J 2
(-2566 1063);
DISPLAY 0.574468 (-2566 1063);
PAINT GREEN (-2566 1063);
DISPLAY INVISIBLE (-2566 1063);
FORCEPROP 1 LAST LOCATION C6738
J 0
(-2200 1050);
DISPLAY 1.021277 (-2200 1050);
DISPLAY INVISIBLE (-2200 1050);
FORCEADD Q_CAP_DIFFBUS..2
R 2
(-2450 825);
FORCEPROP 1 LAST LOCATION C6739
J 2
(-2175 825);
DISPLAY 0.723404 (-2175 825);
PAINT GREEN (-2175 825);
FORCEPROP 2 LAST $SEC 1
J 2
(-2275 900);
DISPLAY 0.680851 (-2275 900);
PAINT MONO (-2275 900);
DISPLAY INVISIBLE (-2275 900);
FORCEPROP 2 LAST CDS_SEC 1
J 2
(-2275 900);
DISPLAY 0.680851 (-2275 900);
DISPLAY INVISIBLE (-2275 900);
FORCEPROP 2 LASTPIN (-2375 825) $PN 1
J 0
(-2365 835);
DISPLAY 0.808511 (-2365 835);
FORCEPROP 2 LASTPIN (-2525 825) $PN 2
J 2
(-2535 835);
DISPLAY 0.808511 (-2535 835);
FORCEPROP 2 LAST VALUE DIFF BUS_0.22UF
J 2
(-2600 825);
DISPLAY 0.553191 (-2600 825);
FORCEPROP 1 LAST CDS_LMAN_SYM_OUTLINE -25,50,25,-50
J 2
(-2450 825);
DISPLAY 0.468085 (-2450 825);
PAINT GREEN (-2450 825);
DISPLAY INVISIBLE (-2450 825);
FORCEPROP 2 LAST CDS_LIB pure_quanta
J 2
(-2450 825);
DISPLAY INVISIBLE (-2450 825);
FORCEPROP 1 LAST PIN_NAMES_ROTATE TRUE
J 2
(-2450 825);
DISPLAY 0.489362 (-2450 825);
PAINT GREEN (-2450 825);
DISPLAY INVISIBLE (-2450 825);
FORCEPROP 2 LAST VOLTAGE 6.3V
J 2
(-2800 875);
DISPLAY 0.553191 (-2800 875);
DISPLAY INVISIBLE (-2800 875);
FORCEPROP 1 LAST MATERIAL X6S
J 2
(-2441 904);
DISPLAY 0.574468 (-2441 904);
PAINT GREEN (-2441 904);
DISPLAY INVISIBLE (-2441 904);
FORCEPROP 2 LAST PACK_TYPE C0201
J 2
(-2625 875);
DISPLAY 0.553191 (-2625 875);
DISPLAY INVISIBLE (-2625 875);
FORCEPROP 2 LAST TOLERANCE 20%
J 2
(-2525 875);
DISPLAY 0.553191 (-2525 875);
DISPLAY INVISIBLE (-2525 875);
FORCEPROP 1 LAST PATH I17
J 2
(-2450 825);
DISPLAY 0.723404 (-2450 825);
DISPLAY INVISIBLE (-2450 825);
FORCEPROP 1 LAST PART_NUMBER SP_CH4221MEE01
J 2
(-2566 913);
DISPLAY 0.574468 (-2566 913);
PAINT GREEN (-2566 913);
DISPLAY INVISIBLE (-2566 913);
FORCEPROP 1 LAST LOCATION C6739
J 0
(-2200 900);
DISPLAY 1.021277 (-2200 900);
DISPLAY INVISIBLE (-2200 900);
FORCEADD Q_CAP_DIFFBUS..2
R 2
(-2450 775);
FORCEPROP 1 LAST LOCATION C6740
J 2
(-2175 775);
DISPLAY 0.723404 (-2175 775);
PAINT GREEN (-2175 775);
FORCEPROP 2 LAST $SEC 1
J 2
(-2275 850);
DISPLAY 0.680851 (-2275 850);
PAINT MONO (-2275 850);
DISPLAY INVISIBLE (-2275 850);
FORCEPROP 2 LAST CDS_SEC 1
J 2
(-2275 850);
DISPLAY 0.680851 (-2275 850);
DISPLAY INVISIBLE (-2275 850);
FORCEPROP 2 LASTPIN (-2375 775) $PN 1
J 0
(-2365 785);
DISPLAY 0.808511 (-2365 785);
FORCEPROP 2 LASTPIN (-2525 775) $PN 2
J 2
(-2535 785);
DISPLAY 0.808511 (-2535 785);
FORCEPROP 2 LAST VALUE DIFF BUS_0.22UF
J 2
(-2600 775);
DISPLAY 0.553191 (-2600 775);
FORCEPROP 1 LAST CDS_LMAN_SYM_OUTLINE -25,50,25,-50
J 2
(-2450 775);
DISPLAY 0.468085 (-2450 775);
PAINT GREEN (-2450 775);
DISPLAY INVISIBLE (-2450 775);
FORCEPROP 2 LAST CDS_LIB pure_quanta
J 2
(-2450 775);
DISPLAY INVISIBLE (-2450 775);
FORCEPROP 1 LAST PIN_NAMES_ROTATE TRUE
J 2
(-2450 775);
DISPLAY 0.489362 (-2450 775);
PAINT GREEN (-2450 775);
DISPLAY INVISIBLE (-2450 775);
FORCEPROP 2 LAST VOLTAGE 6.3V
J 2
(-2800 825);
DISPLAY 0.553191 (-2800 825);
DISPLAY INVISIBLE (-2800 825);
FORCEPROP 1 LAST MATERIAL X6S
J 2
(-2441 854);
DISPLAY 0.574468 (-2441 854);
PAINT GREEN (-2441 854);
DISPLAY INVISIBLE (-2441 854);
FORCEPROP 2 LAST PACK_TYPE C0201
J 2
(-2625 825);
DISPLAY 0.553191 (-2625 825);
DISPLAY INVISIBLE (-2625 825);
FORCEPROP 2 LAST TOLERANCE 20%
J 2
(-2525 825);
DISPLAY 0.553191 (-2525 825);
DISPLAY INVISIBLE (-2525 825);
FORCEPROP 1 LAST PATH I18
J 2
(-2450 775);
DISPLAY 0.723404 (-2450 775);
DISPLAY INVISIBLE (-2450 775);
FORCEPROP 1 LAST PART_NUMBER SP_CH4221MEE01
J 2
(-2566 863);
DISPLAY 0.574468 (-2566 863);
PAINT GREEN (-2566 863);
DISPLAY INVISIBLE (-2566 863);
FORCEPROP 1 LAST LOCATION C6740
J 0
(-2200 850);
DISPLAY 1.021277 (-2200 850);
DISPLAY INVISIBLE (-2200 850);
FORCEADD TAP..1
(-1900 825);
FORCEPROP 3 LASTPIN (-1950 825) SIG_NAME P5E_CPU1_P3_TX_BUF_C_DP<7>
J 0
(-1940 835);
DISPLAY 0.659574 (-1940 835);
PAINT MONO (-1940 835);
DISPLAY INVISIBLE (-1940 835);
FORCEPROP 1 LASTPIN (-1950 825) BN 7
J 0
(-1962 833);
DISPLAY 0.680851 (-1962 833);
PAINT GREEN (-1962 833);
FORCEPROP 2 LAST CDS_LIB standard
J 0
(-1900 825);
DISPLAY INVISIBLE (-1900 825);
FORCEPROP 1 LAST BODY_TYPE PLUMBING
J 0
(-1900 875);
DISPLAY 0.872340 (-1900 875);
PAINT GREEN (-1900 875);
DISPLAY INVISIBLE (-1900 875);
FORCEPROP 1 LAST HDL_TAP TRUE
J 0
(-1575 700);
DISPLAY 0.872340 (-1575 700);
DISPLAY INVISIBLE (-1575 700);
FORCEPROP 1 LAST PATH I19
J 0
(-1902 825);
DISPLAY 0.872340 (-1902 825);
PAINT GREEN (-1902 825);
DISPLAY INVISIBLE (-1902 825);
FORCEADD OFFPAGE..1
(-4375 2250);
FORCEPROP 2 LAST $XR0 353 
J 0
(-4627 2250);
DISPLAY 0.638298 (-4627 2250);
PAINT MONO (-4627 2250);
FORCEPROP 2 LAST CDS_LIB standard
J 0
(-4375 2250);
DISPLAY INVISIBLE (-4375 2250);
FORCEPROP 1 LAST OFFPAGE TRUE
J 0
(-4050 2125);
DISPLAY 0.872340 (-4050 2125);
DISPLAY INVISIBLE (-4050 2125);
FORCEPROP 1 LAST COMMENT_BODY TRUE
J 0
(-4250 2150);
DISPLAY 0.872340 (-4250 2150);
PAINT GREEN (-4250 2150);
DISPLAY INVISIBLE (-4250 2150);
FORCEPROP 2 LAST PATH I2
J 0
(-4625 2300);
DISPLAY 0.680851 (-4625 2300);
DISPLAY INVISIBLE (-4625 2300);
FORCEADD TAP..1
(-1700 775);
FORCEPROP 3 LASTPIN (-1750 775) SIG_NAME P5E_CPU1_P3_TX_BUF_C_DN<7>
J 0
(-1740 785);
DISPLAY 0.659574 (-1740 785);
PAINT MONO (-1740 785);
DISPLAY INVISIBLE (-1740 785);
FORCEPROP 1 LASTPIN (-1750 775) BN 7
J 0
(-1762 783);
DISPLAY 0.680851 (-1762 783);
PAINT GREEN (-1762 783);
FORCEPROP 2 LAST CDS_LIB standard
J 0
(-1700 775);
DISPLAY INVISIBLE (-1700 775);
FORCEPROP 1 LAST BODY_TYPE PLUMBING
J 0
(-1700 825);
DISPLAY 0.872340 (-1700 825);
PAINT GREEN (-1700 825);
DISPLAY INVISIBLE (-1700 825);
FORCEPROP 1 LAST HDL_TAP TRUE
J 0
(-1375 650);
DISPLAY 0.872340 (-1375 650);
DISPLAY INVISIBLE (-1375 650);
FORCEPROP 1 LAST PATH I20
J 0
(-1702 775);
DISPLAY 0.872340 (-1702 775);
PAINT GREEN (-1702 775);
DISPLAY INVISIBLE (-1702 775);
FORCEADD TAP..1
(-1700 975);
FORCEPROP 3 LASTPIN (-1750 975) SIG_NAME P5E_CPU1_P3_TX_BUF_C_DN<6>
J 0
(-1740 985);
DISPLAY 0.659574 (-1740 985);
PAINT MONO (-1740 985);
DISPLAY INVISIBLE (-1740 985);
FORCEPROP 1 LASTPIN (-1750 975) BN 6
J 0
(-1762 983);
DISPLAY 0.680851 (-1762 983);
PAINT GREEN (-1762 983);
FORCEPROP 2 LAST CDS_LIB standard
J 0
(-1700 975);
DISPLAY INVISIBLE (-1700 975);
FORCEPROP 1 LAST BODY_TYPE PLUMBING
J 0
(-1700 1025);
DISPLAY 0.872340 (-1700 1025);
PAINT GREEN (-1700 1025);
DISPLAY INVISIBLE (-1700 1025);
FORCEPROP 1 LAST HDL_TAP TRUE
J 0
(-1375 850);
DISPLAY 0.872340 (-1375 850);
DISPLAY INVISIBLE (-1375 850);
FORCEPROP 1 LAST PATH I21
J 0
(-1702 975);
DISPLAY 0.872340 (-1702 975);
PAINT GREEN (-1702 975);
DISPLAY INVISIBLE (-1702 975);
FORCEADD Q_CAP_DIFFBUS..2
R 2
(-2450 1025);
FORCEPROP 1 LAST LOCATION C6737
J 2
(-2175 1025);
DISPLAY 0.723404 (-2175 1025);
PAINT GREEN (-2175 1025);
FORCEPROP 2 LAST $SEC 1
J 2
(-2275 1100);
DISPLAY 0.680851 (-2275 1100);
PAINT MONO (-2275 1100);
DISPLAY INVISIBLE (-2275 1100);
FORCEPROP 2 LAST CDS_SEC 1
J 2
(-2275 1100);
DISPLAY 0.680851 (-2275 1100);
DISPLAY INVISIBLE (-2275 1100);
FORCEPROP 2 LASTPIN (-2375 1025) $PN 1
J 0
(-2365 1035);
DISPLAY 0.808511 (-2365 1035);
FORCEPROP 2 LASTPIN (-2525 1025) $PN 2
J 2
(-2535 1035);
DISPLAY 0.808511 (-2535 1035);
FORCEPROP 2 LAST VALUE DIFF BUS_0.22UF
J 2
(-2600 1025);
DISPLAY 0.553191 (-2600 1025);
FORCEPROP 2 LAST CDS_LIB pure_quanta
J 2
(-2450 1025);
DISPLAY INVISIBLE (-2450 1025);
FORCEPROP 1 LAST CDS_LMAN_SYM_OUTLINE -25,50,25,-50
J 2
(-2450 1025);
DISPLAY 0.468085 (-2450 1025);
PAINT GREEN (-2450 1025);
DISPLAY INVISIBLE (-2450 1025);
FORCEPROP 1 LAST PIN_NAMES_ROTATE TRUE
J 2
(-2450 1025);
DISPLAY 0.489362 (-2450 1025);
PAINT GREEN (-2450 1025);
DISPLAY INVISIBLE (-2450 1025);
FORCEPROP 2 LAST VOLTAGE 6.3V
J 2
(-2800 1075);
DISPLAY 0.553191 (-2800 1075);
DISPLAY INVISIBLE (-2800 1075);
FORCEPROP 1 LAST MATERIAL X6S
J 2
(-2441 1104);
DISPLAY 0.574468 (-2441 1104);
PAINT GREEN (-2441 1104);
DISPLAY INVISIBLE (-2441 1104);
FORCEPROP 2 LAST PACK_TYPE C0201
J 2
(-2625 1075);
DISPLAY 0.553191 (-2625 1075);
DISPLAY INVISIBLE (-2625 1075);
FORCEPROP 2 LAST TOLERANCE 20%
J 2
(-2525 1075);
DISPLAY 0.553191 (-2525 1075);
DISPLAY INVISIBLE (-2525 1075);
FORCEPROP 1 LAST PATH I22
J 2
(-2450 1025);
DISPLAY 0.723404 (-2450 1025);
DISPLAY INVISIBLE (-2450 1025);
FORCEPROP 1 LAST PART_NUMBER SP_CH4221MEE01
J 2
(-2566 1113);
DISPLAY 0.574468 (-2566 1113);
PAINT GREEN (-2566 1113);
DISPLAY INVISIBLE (-2566 1113);
FORCEPROP 1 LAST LOCATION C6737
J 0
(-2200 1100);
DISPLAY 1.021277 (-2200 1100);
DISPLAY INVISIBLE (-2200 1100);
FORCEADD Q_CAP_DIFFBUS..2
R 2
(-2450 1175);
FORCEPROP 1 LAST LOCATION C6736
J 2
(-2175 1175);
DISPLAY 0.723404 (-2175 1175);
PAINT GREEN (-2175 1175);
FORCEPROP 2 LAST $SEC 1
J 2
(-2275 1250);
DISPLAY 0.680851 (-2275 1250);
PAINT MONO (-2275 1250);
DISPLAY INVISIBLE (-2275 1250);
FORCEPROP 2 LAST CDS_SEC 1
J 2
(-2275 1250);
DISPLAY 0.680851 (-2275 1250);
DISPLAY INVISIBLE (-2275 1250);
FORCEPROP 2 LASTPIN (-2375 1175) $PN 1
J 0
(-2365 1185);
DISPLAY 0.808511 (-2365 1185);
FORCEPROP 2 LASTPIN (-2525 1175) $PN 2
J 2
(-2535 1185);
DISPLAY 0.808511 (-2535 1185);
FORCEPROP 2 LAST VALUE DIFF BUS_0.22UF
J 2
(-2600 1175);
DISPLAY 0.553191 (-2600 1175);
FORCEPROP 1 LAST CDS_LMAN_SYM_OUTLINE -25,50,25,-50
J 2
(-2450 1175);
DISPLAY 0.468085 (-2450 1175);
PAINT GREEN (-2450 1175);
DISPLAY INVISIBLE (-2450 1175);
FORCEPROP 2 LAST CDS_LIB pure_quanta
J 2
(-2450 1175);
DISPLAY INVISIBLE (-2450 1175);
FORCEPROP 1 LAST PIN_NAMES_ROTATE TRUE
J 2
(-2450 1175);
DISPLAY 0.489362 (-2450 1175);
PAINT GREEN (-2450 1175);
DISPLAY INVISIBLE (-2450 1175);
FORCEPROP 2 LAST VOLTAGE 6.3V
J 2
(-2800 1225);
DISPLAY 0.553191 (-2800 1225);
DISPLAY INVISIBLE (-2800 1225);
FORCEPROP 1 LAST MATERIAL X6S
J 2
(-2441 1254);
DISPLAY 0.574468 (-2441 1254);
PAINT GREEN (-2441 1254);
DISPLAY INVISIBLE (-2441 1254);
FORCEPROP 2 LAST PACK_TYPE C0201
J 2
(-2625 1225);
DISPLAY 0.553191 (-2625 1225);
DISPLAY INVISIBLE (-2625 1225);
FORCEPROP 2 LAST TOLERANCE 20%
J 2
(-2525 1225);
DISPLAY 0.553191 (-2525 1225);
DISPLAY INVISIBLE (-2525 1225);
FORCEPROP 1 LAST PATH I23
J 2
(-2450 1175);
DISPLAY 0.723404 (-2450 1175);
DISPLAY INVISIBLE (-2450 1175);
FORCEPROP 1 LAST PART_NUMBER SP_CH4221MEE01
J 2
(-2566 1263);
DISPLAY 0.574468 (-2566 1263);
PAINT GREEN (-2566 1263);
DISPLAY INVISIBLE (-2566 1263);
FORCEPROP 1 LAST LOCATION C6736
J 0
(-2200 1250);
DISPLAY 1.021277 (-2200 1250);
DISPLAY INVISIBLE (-2200 1250);
FORCEADD Q_CAP_DIFFBUS..2
R 2
(-2450 1225);
FORCEPROP 1 LAST LOCATION C6735
J 2
(-2175 1225);
DISPLAY 0.723404 (-2175 1225);
PAINT GREEN (-2175 1225);
FORCEPROP 2 LAST $SEC 1
J 2
(-2275 1300);
DISPLAY 0.680851 (-2275 1300);
PAINT MONO (-2275 1300);
DISPLAY INVISIBLE (-2275 1300);
FORCEPROP 2 LAST CDS_SEC 1
J 2
(-2275 1300);
DISPLAY 0.680851 (-2275 1300);
DISPLAY INVISIBLE (-2275 1300);
FORCEPROP 2 LASTPIN (-2375 1225) $PN 1
J 0
(-2365 1235);
DISPLAY 0.808511 (-2365 1235);
FORCEPROP 2 LASTPIN (-2525 1225) $PN 2
J 2
(-2535 1235);
DISPLAY 0.808511 (-2535 1235);
FORCEPROP 2 LAST VALUE DIFF BUS_0.22UF
J 2
(-2600 1225);
DISPLAY 0.553191 (-2600 1225);
FORCEPROP 1 LAST CDS_LMAN_SYM_OUTLINE -25,50,25,-50
J 2
(-2450 1225);
DISPLAY 0.468085 (-2450 1225);
PAINT GREEN (-2450 1225);
DISPLAY INVISIBLE (-2450 1225);
FORCEPROP 2 LAST CDS_LIB pure_quanta
J 2
(-2450 1225);
DISPLAY INVISIBLE (-2450 1225);
FORCEPROP 1 LAST PIN_NAMES_ROTATE TRUE
J 2
(-2450 1225);
DISPLAY 0.489362 (-2450 1225);
PAINT GREEN (-2450 1225);
DISPLAY INVISIBLE (-2450 1225);
FORCEPROP 2 LAST VOLTAGE 6.3V
J 2
(-2800 1275);
DISPLAY 0.553191 (-2800 1275);
DISPLAY INVISIBLE (-2800 1275);
FORCEPROP 1 LAST MATERIAL X6S
J 2
(-2441 1304);
DISPLAY 0.574468 (-2441 1304);
PAINT GREEN (-2441 1304);
DISPLAY INVISIBLE (-2441 1304);
FORCEPROP 2 LAST PACK_TYPE C0201
J 2
(-2625 1275);
DISPLAY 0.553191 (-2625 1275);
DISPLAY INVISIBLE (-2625 1275);
FORCEPROP 2 LAST TOLERANCE 20%
J 2
(-2525 1275);
DISPLAY 0.553191 (-2525 1275);
DISPLAY INVISIBLE (-2525 1275);
FORCEPROP 1 LAST PATH I24
J 2
(-2450 1225);
DISPLAY 0.723404 (-2450 1225);
DISPLAY INVISIBLE (-2450 1225);
FORCEPROP 1 LAST PART_NUMBER SP_CH4221MEE01
J 2
(-2566 1313);
DISPLAY 0.574468 (-2566 1313);
PAINT GREEN (-2566 1313);
DISPLAY INVISIBLE (-2566 1313);
FORCEPROP 1 LAST LOCATION C6735
J 0
(-2200 1300);
DISPLAY 1.021277 (-2200 1300);
DISPLAY INVISIBLE (-2200 1300);
FORCEADD Q_CAP_DIFFBUS..2
R 2
(-2450 1375);
FORCEPROP 1 LAST LOCATION C6734
J 2
(-2175 1375);
DISPLAY 0.723404 (-2175 1375);
PAINT GREEN (-2175 1375);
FORCEPROP 2 LAST $SEC 1
J 2
(-2275 1450);
DISPLAY 0.680851 (-2275 1450);
PAINT MONO (-2275 1450);
DISPLAY INVISIBLE (-2275 1450);
FORCEPROP 2 LAST CDS_SEC 1
J 2
(-2275 1450);
DISPLAY 0.680851 (-2275 1450);
DISPLAY INVISIBLE (-2275 1450);
FORCEPROP 2 LASTPIN (-2375 1375) $PN 1
J 0
(-2365 1385);
DISPLAY 0.808511 (-2365 1385);
FORCEPROP 2 LASTPIN (-2525 1375) $PN 2
J 2
(-2535 1385);
DISPLAY 0.808511 (-2535 1385);
FORCEPROP 2 LAST VALUE DIFF BUS_0.22UF
J 2
(-2600 1375);
DISPLAY 0.553191 (-2600 1375);
FORCEPROP 2 LAST CDS_LIB pure_quanta
J 2
(-2450 1375);
DISPLAY INVISIBLE (-2450 1375);
FORCEPROP 1 LAST CDS_LMAN_SYM_OUTLINE -25,50,25,-50
J 2
(-2450 1375);
DISPLAY 0.468085 (-2450 1375);
PAINT GREEN (-2450 1375);
DISPLAY INVISIBLE (-2450 1375);
FORCEPROP 1 LAST PIN_NAMES_ROTATE TRUE
J 2
(-2450 1375);
DISPLAY 0.489362 (-2450 1375);
PAINT GREEN (-2450 1375);
DISPLAY INVISIBLE (-2450 1375);
FORCEPROP 2 LAST VOLTAGE 6.3V
J 2
(-2800 1425);
DISPLAY 0.553191 (-2800 1425);
DISPLAY INVISIBLE (-2800 1425);
FORCEPROP 1 LAST MATERIAL X6S
J 2
(-2441 1454);
DISPLAY 0.574468 (-2441 1454);
PAINT GREEN (-2441 1454);
DISPLAY INVISIBLE (-2441 1454);
FORCEPROP 2 LAST PACK_TYPE C0201
J 2
(-2625 1425);
DISPLAY 0.553191 (-2625 1425);
DISPLAY INVISIBLE (-2625 1425);
FORCEPROP 2 LAST TOLERANCE 20%
J 2
(-2525 1425);
DISPLAY 0.553191 (-2525 1425);
DISPLAY INVISIBLE (-2525 1425);
FORCEPROP 1 LAST PATH I25
J 2
(-2450 1375);
DISPLAY 0.723404 (-2450 1375);
DISPLAY INVISIBLE (-2450 1375);
FORCEPROP 1 LAST PART_NUMBER SP_CH4221MEE01
J 2
(-2566 1463);
DISPLAY 0.574468 (-2566 1463);
PAINT GREEN (-2566 1463);
DISPLAY INVISIBLE (-2566 1463);
FORCEPROP 1 LAST LOCATION C6734
J 0
(-2200 1450);
DISPLAY 1.021277 (-2200 1450);
DISPLAY INVISIBLE (-2200 1450);
FORCEADD Q_CAP_DIFFBUS..2
R 2
(-2450 1425);
FORCEPROP 1 LAST LOCATION C6733
J 2
(-2175 1425);
DISPLAY 0.723404 (-2175 1425);
PAINT GREEN (-2175 1425);
FORCEPROP 2 LAST $SEC 1
J 2
(-2275 1500);
DISPLAY 0.680851 (-2275 1500);
PAINT MONO (-2275 1500);
DISPLAY INVISIBLE (-2275 1500);
FORCEPROP 2 LAST CDS_SEC 1
J 2
(-2275 1500);
DISPLAY 0.680851 (-2275 1500);
DISPLAY INVISIBLE (-2275 1500);
FORCEPROP 2 LASTPIN (-2375 1425) $PN 1
J 0
(-2365 1435);
DISPLAY 0.808511 (-2365 1435);
FORCEPROP 2 LASTPIN (-2525 1425) $PN 2
J 2
(-2535 1435);
DISPLAY 0.808511 (-2535 1435);
FORCEPROP 2 LAST VALUE DIFF BUS_0.22UF
J 2
(-2600 1425);
DISPLAY 0.553191 (-2600 1425);
FORCEPROP 2 LAST CDS_LIB pure_quanta
J 2
(-2450 1425);
DISPLAY INVISIBLE (-2450 1425);
FORCEPROP 1 LAST CDS_LMAN_SYM_OUTLINE -25,50,25,-50
J 2
(-2450 1425);
DISPLAY 0.468085 (-2450 1425);
PAINT GREEN (-2450 1425);
DISPLAY INVISIBLE (-2450 1425);
FORCEPROP 1 LAST PIN_NAMES_ROTATE TRUE
J 2
(-2450 1425);
DISPLAY 0.489362 (-2450 1425);
PAINT GREEN (-2450 1425);
DISPLAY INVISIBLE (-2450 1425);
FORCEPROP 2 LAST VOLTAGE 6.3V
J 2
(-2800 1475);
DISPLAY 0.553191 (-2800 1475);
DISPLAY INVISIBLE (-2800 1475);
FORCEPROP 1 LAST MATERIAL X6S
J 2
(-2441 1504);
DISPLAY 0.574468 (-2441 1504);
PAINT GREEN (-2441 1504);
DISPLAY INVISIBLE (-2441 1504);
FORCEPROP 2 LAST PACK_TYPE C0201
J 2
(-2625 1475);
DISPLAY 0.553191 (-2625 1475);
DISPLAY INVISIBLE (-2625 1475);
FORCEPROP 2 LAST TOLERANCE 20%
J 2
(-2525 1475);
DISPLAY 0.553191 (-2525 1475);
DISPLAY INVISIBLE (-2525 1475);
FORCEPROP 1 LAST PATH I26
J 2
(-2450 1425);
DISPLAY 0.723404 (-2450 1425);
DISPLAY INVISIBLE (-2450 1425);
FORCEPROP 1 LAST PART_NUMBER SP_CH4221MEE01
J 2
(-2566 1513);
DISPLAY 0.574468 (-2566 1513);
PAINT GREEN (-2566 1513);
DISPLAY INVISIBLE (-2566 1513);
FORCEPROP 1 LAST LOCATION C6733
J 0
(-2200 1500);
DISPLAY 1.021277 (-2200 1500);
DISPLAY INVISIBLE (-2200 1500);
FORCEADD Q_CAP_DIFFBUS..2
R 2
(-2450 1625);
FORCEPROP 1 LAST LOCATION C6731
J 2
(-2175 1625);
DISPLAY 0.723404 (-2175 1625);
PAINT GREEN (-2175 1625);
FORCEPROP 2 LAST $SEC 1
J 2
(-2275 1700);
DISPLAY 0.680851 (-2275 1700);
PAINT MONO (-2275 1700);
DISPLAY INVISIBLE (-2275 1700);
FORCEPROP 2 LAST CDS_SEC 1
J 2
(-2275 1700);
DISPLAY 0.680851 (-2275 1700);
DISPLAY INVISIBLE (-2275 1700);
FORCEPROP 2 LASTPIN (-2375 1625) $PN 1
J 0
(-2365 1635);
DISPLAY 0.808511 (-2365 1635);
FORCEPROP 2 LASTPIN (-2525 1625) $PN 2
J 2
(-2535 1635);
DISPLAY 0.808511 (-2535 1635);
FORCEPROP 2 LAST VALUE DIFF BUS_0.22UF
J 2
(-2600 1625);
DISPLAY 0.553191 (-2600 1625);
FORCEPROP 1 LAST CDS_LMAN_SYM_OUTLINE -25,50,25,-50
J 2
(-2450 1625);
DISPLAY 0.468085 (-2450 1625);
PAINT GREEN (-2450 1625);
DISPLAY INVISIBLE (-2450 1625);
FORCEPROP 2 LAST CDS_LIB pure_quanta
J 2
(-2450 1625);
DISPLAY INVISIBLE (-2450 1625);
FORCEPROP 1 LAST PIN_NAMES_ROTATE TRUE
J 2
(-2450 1625);
DISPLAY 0.489362 (-2450 1625);
PAINT GREEN (-2450 1625);
DISPLAY INVISIBLE (-2450 1625);
FORCEPROP 2 LAST VOLTAGE 6.3V
J 2
(-2800 1675);
DISPLAY 0.553191 (-2800 1675);
DISPLAY INVISIBLE (-2800 1675);
FORCEPROP 1 LAST MATERIAL X6S
J 2
(-2441 1704);
DISPLAY 0.574468 (-2441 1704);
PAINT GREEN (-2441 1704);
DISPLAY INVISIBLE (-2441 1704);
FORCEPROP 2 LAST PACK_TYPE C0201
J 2
(-2625 1675);
DISPLAY 0.553191 (-2625 1675);
DISPLAY INVISIBLE (-2625 1675);
FORCEPROP 2 LAST TOLERANCE 20%
J 2
(-2525 1675);
DISPLAY 0.553191 (-2525 1675);
DISPLAY INVISIBLE (-2525 1675);
FORCEPROP 1 LAST PATH I27
J 2
(-2450 1625);
DISPLAY 0.723404 (-2450 1625);
DISPLAY INVISIBLE (-2450 1625);
FORCEPROP 1 LAST PART_NUMBER SP_CH4221MEE01
J 2
(-2566 1713);
DISPLAY 0.574468 (-2566 1713);
PAINT GREEN (-2566 1713);
DISPLAY INVISIBLE (-2566 1713);
FORCEPROP 1 LAST LOCATION C6731
J 0
(-2200 1700);
DISPLAY 1.021277 (-2200 1700);
DISPLAY INVISIBLE (-2200 1700);
FORCEADD Q_CAP_DIFFBUS..2
R 2
(-2450 1575);
FORCEPROP 1 LAST LOCATION C6732
J 2
(-2175 1575);
DISPLAY 0.723404 (-2175 1575);
PAINT GREEN (-2175 1575);
FORCEPROP 2 LAST $SEC 1
J 2
(-2275 1650);
DISPLAY 0.680851 (-2275 1650);
PAINT MONO (-2275 1650);
DISPLAY INVISIBLE (-2275 1650);
FORCEPROP 2 LAST CDS_SEC 1
J 2
(-2275 1650);
DISPLAY 0.680851 (-2275 1650);
DISPLAY INVISIBLE (-2275 1650);
FORCEPROP 2 LASTPIN (-2375 1575) $PN 1
J 0
(-2365 1585);
DISPLAY 0.808511 (-2365 1585);
FORCEPROP 2 LASTPIN (-2525 1575) $PN 2
J 2
(-2535 1585);
DISPLAY 0.808511 (-2535 1585);
FORCEPROP 2 LAST VALUE DIFF BUS_0.22UF
J 2
(-2600 1575);
DISPLAY 0.553191 (-2600 1575);
FORCEPROP 1 LAST CDS_LMAN_SYM_OUTLINE -25,50,25,-50
J 2
(-2450 1575);
DISPLAY 0.468085 (-2450 1575);
PAINT GREEN (-2450 1575);
DISPLAY INVISIBLE (-2450 1575);
FORCEPROP 2 LAST CDS_LIB pure_quanta
J 2
(-2450 1575);
DISPLAY INVISIBLE (-2450 1575);
FORCEPROP 1 LAST PIN_NAMES_ROTATE TRUE
J 2
(-2450 1575);
DISPLAY 0.489362 (-2450 1575);
PAINT GREEN (-2450 1575);
DISPLAY INVISIBLE (-2450 1575);
FORCEPROP 2 LAST VOLTAGE 6.3V
J 2
(-2800 1625);
DISPLAY 0.553191 (-2800 1625);
DISPLAY INVISIBLE (-2800 1625);
FORCEPROP 1 LAST MATERIAL X6S
J 2
(-2441 1654);
DISPLAY 0.574468 (-2441 1654);
PAINT GREEN (-2441 1654);
DISPLAY INVISIBLE (-2441 1654);
FORCEPROP 2 LAST PACK_TYPE C0201
J 2
(-2625 1625);
DISPLAY 0.553191 (-2625 1625);
DISPLAY INVISIBLE (-2625 1625);
FORCEPROP 2 LAST TOLERANCE 20%
J 2
(-2525 1625);
DISPLAY 0.553191 (-2525 1625);
DISPLAY INVISIBLE (-2525 1625);
FORCEPROP 1 LAST PATH I28
J 2
(-2450 1575);
DISPLAY 0.723404 (-2450 1575);
DISPLAY INVISIBLE (-2450 1575);
FORCEPROP 1 LAST PART_NUMBER SP_CH4221MEE01
J 2
(-2566 1663);
DISPLAY 0.574468 (-2566 1663);
PAINT GREEN (-2566 1663);
DISPLAY INVISIBLE (-2566 1663);
FORCEPROP 1 LAST LOCATION C6732
J 0
(-2200 1650);
DISPLAY 1.021277 (-2200 1650);
DISPLAY INVISIBLE (-2200 1650);
FORCEADD Q_CAP_DIFFBUS..2
R 2
(-2450 1775);
FORCEPROP 1 LAST LOCATION C6730
J 2
(-2175 1775);
DISPLAY 0.723404 (-2175 1775);
PAINT GREEN (-2175 1775);
FORCEPROP 2 LAST $SEC 1
J 2
(-2275 1850);
DISPLAY 0.680851 (-2275 1850);
PAINT MONO (-2275 1850);
DISPLAY INVISIBLE (-2275 1850);
FORCEPROP 2 LAST CDS_SEC 1
J 2
(-2275 1850);
DISPLAY 0.680851 (-2275 1850);
DISPLAY INVISIBLE (-2275 1850);
FORCEPROP 2 LASTPIN (-2375 1775) $PN 1
J 0
(-2365 1785);
DISPLAY 0.808511 (-2365 1785);
FORCEPROP 2 LASTPIN (-2525 1775) $PN 2
J 2
(-2535 1785);
DISPLAY 0.808511 (-2535 1785);
FORCEPROP 2 LAST VALUE DIFF BUS_0.22UF
J 2
(-2600 1775);
DISPLAY 0.553191 (-2600 1775);
FORCEPROP 1 LAST CDS_LMAN_SYM_OUTLINE -25,50,25,-50
J 2
(-2450 1775);
DISPLAY 0.468085 (-2450 1775);
PAINT GREEN (-2450 1775);
DISPLAY INVISIBLE (-2450 1775);
FORCEPROP 2 LAST CDS_LIB pure_quanta
J 2
(-2450 1775);
DISPLAY INVISIBLE (-2450 1775);
FORCEPROP 1 LAST PIN_NAMES_ROTATE TRUE
J 2
(-2450 1775);
DISPLAY 0.489362 (-2450 1775);
PAINT GREEN (-2450 1775);
DISPLAY INVISIBLE (-2450 1775);
FORCEPROP 2 LAST VOLTAGE 6.3V
J 2
(-2800 1825);
DISPLAY 0.553191 (-2800 1825);
DISPLAY INVISIBLE (-2800 1825);
FORCEPROP 1 LAST MATERIAL X6S
J 2
(-2441 1854);
DISPLAY 0.574468 (-2441 1854);
PAINT GREEN (-2441 1854);
DISPLAY INVISIBLE (-2441 1854);
FORCEPROP 2 LAST PACK_TYPE C0201
J 2
(-2625 1825);
DISPLAY 0.553191 (-2625 1825);
DISPLAY INVISIBLE (-2625 1825);
FORCEPROP 2 LAST TOLERANCE 20%
J 2
(-2525 1825);
DISPLAY 0.553191 (-2525 1825);
DISPLAY INVISIBLE (-2525 1825);
FORCEPROP 1 LAST PATH I29
J 2
(-2450 1775);
DISPLAY 0.723404 (-2450 1775);
DISPLAY INVISIBLE (-2450 1775);
FORCEPROP 1 LAST PART_NUMBER SP_CH4221MEE01
J 2
(-2566 1863);
DISPLAY 0.574468 (-2566 1863);
PAINT GREEN (-2566 1863);
DISPLAY INVISIBLE (-2566 1863);
FORCEPROP 1 LAST LOCATION C6730
J 0
(-2200 1850);
DISPLAY 1.021277 (-2200 1850);
DISPLAY INVISIBLE (-2200 1850);
FORCEADD TAP..1
R 2
(-3425 775);
FORCEPROP 3 LASTPIN (-3375 775) SIG_NAME P5E_CPU1_P3_TX_BUF_DN<7>
J 0
(-3365 785);
DISPLAY 0.659574 (-3365 785);
PAINT MONO (-3365 785);
DISPLAY INVISIBLE (-3365 785);
FORCEPROP 1 LASTPIN (-3375 775) BN 7
J 2
(-3363 783);
DISPLAY 0.680851 (-3363 783);
PAINT GREEN (-3363 783);
FORCEPROP 2 LAST CDS_LIB standard
J 0
(-3425 775);
DISPLAY INVISIBLE (-3425 775);
FORCEPROP 1 LAST BODY_TYPE PLUMBING
J 2
(-3425 825);
DISPLAY 0.872340 (-3425 825);
PAINT GREEN (-3425 825);
DISPLAY INVISIBLE (-3425 825);
FORCEPROP 1 LAST HDL_TAP TRUE
J 2
(-3750 650);
DISPLAY 0.872340 (-3750 650);
DISPLAY INVISIBLE (-3750 650);
FORCEPROP 1 LAST PATH I3
J 2
(-3423 775);
DISPLAY 0.872340 (-3423 775);
PAINT GREEN (-3423 775);
DISPLAY INVISIBLE (-3423 775);
FORCEADD Q_CAP_DIFFBUS..2
R 2
(-2450 1975);
FORCEPROP 1 LAST LOCATION C6728
J 2
(-2150 1975);
DISPLAY 0.723404 (-2150 1975);
PAINT GREEN (-2150 1975);
FORCEPROP 2 LAST $SEC 1
J 2
(-2275 2050);
DISPLAY 0.680851 (-2275 2050);
PAINT MONO (-2275 2050);
DISPLAY INVISIBLE (-2275 2050);
FORCEPROP 2 LAST CDS_SEC 1
J 2
(-2275 2050);
DISPLAY 0.680851 (-2275 2050);
DISPLAY INVISIBLE (-2275 2050);
FORCEPROP 2 LASTPIN (-2375 1975) $PN 1
J 0
(-2365 1985);
DISPLAY 0.808511 (-2365 1985);
FORCEPROP 2 LASTPIN (-2525 1975) $PN 2
J 2
(-2535 1985);
DISPLAY 0.808511 (-2535 1985);
FORCEPROP 2 LAST VALUE DIFF BUS_0.22UF
J 2
(-2600 1975);
DISPLAY 0.553191 (-2600 1975);
FORCEPROP 1 LAST CDS_LMAN_SYM_OUTLINE -25,50,25,-50
J 2
(-2450 1975);
DISPLAY 0.468085 (-2450 1975);
PAINT GREEN (-2450 1975);
DISPLAY INVISIBLE (-2450 1975);
FORCEPROP 2 LAST CDS_LIB pure_quanta
J 2
(-2450 1975);
DISPLAY INVISIBLE (-2450 1975);
FORCEPROP 1 LAST PIN_NAMES_ROTATE TRUE
J 2
(-2450 1975);
DISPLAY 0.489362 (-2450 1975);
PAINT GREEN (-2450 1975);
DISPLAY INVISIBLE (-2450 1975);
FORCEPROP 2 LAST VOLTAGE 6.3V
J 2
(-2800 2025);
DISPLAY 0.553191 (-2800 2025);
DISPLAY INVISIBLE (-2800 2025);
FORCEPROP 1 LAST MATERIAL X6S
J 2
(-2441 2054);
DISPLAY 0.574468 (-2441 2054);
PAINT GREEN (-2441 2054);
DISPLAY INVISIBLE (-2441 2054);
FORCEPROP 2 LAST PACK_TYPE C0201
J 2
(-2625 2025);
DISPLAY 0.553191 (-2625 2025);
DISPLAY INVISIBLE (-2625 2025);
FORCEPROP 2 LAST TOLERANCE 20%
J 2
(-2525 2025);
DISPLAY 0.553191 (-2525 2025);
DISPLAY INVISIBLE (-2525 2025);
FORCEPROP 1 LAST PATH I30
J 2
(-2450 1975);
DISPLAY 0.723404 (-2450 1975);
DISPLAY INVISIBLE (-2450 1975);
FORCEPROP 1 LAST PART_NUMBER SP_CH4221MEE01
J 2
(-2566 2063);
DISPLAY 0.574468 (-2566 2063);
PAINT GREEN (-2566 2063);
DISPLAY INVISIBLE (-2566 2063);
FORCEPROP 1 LAST LOCATION C6728
J 0
(-2200 2050);
DISPLAY 1.021277 (-2200 2050);
DISPLAY INVISIBLE (-2200 2050);
FORCEADD Q_CAP_DIFFBUS..2
R 2
(-2450 1825);
FORCEPROP 1 LAST LOCATION C6729
J 2
(-2175 1825);
DISPLAY 0.723404 (-2175 1825);
PAINT GREEN (-2175 1825);
FORCEPROP 2 LAST $SEC 1
J 2
(-2275 1900);
DISPLAY 0.680851 (-2275 1900);
PAINT MONO (-2275 1900);
DISPLAY INVISIBLE (-2275 1900);
FORCEPROP 2 LAST CDS_SEC 1
J 2
(-2275 1900);
DISPLAY 0.680851 (-2275 1900);
DISPLAY INVISIBLE (-2275 1900);
FORCEPROP 2 LASTPIN (-2375 1825) $PN 1
J 0
(-2365 1835);
DISPLAY 0.808511 (-2365 1835);
FORCEPROP 2 LASTPIN (-2525 1825) $PN 2
J 2
(-2535 1835);
DISPLAY 0.808511 (-2535 1835);
FORCEPROP 2 LAST VALUE DIFF BUS_0.22UF
J 2
(-2600 1825);
DISPLAY 0.553191 (-2600 1825);
FORCEPROP 1 LAST CDS_LMAN_SYM_OUTLINE -25,50,25,-50
J 2
(-2450 1825);
DISPLAY 0.468085 (-2450 1825);
PAINT GREEN (-2450 1825);
DISPLAY INVISIBLE (-2450 1825);
FORCEPROP 2 LAST CDS_LIB pure_quanta
J 2
(-2450 1825);
DISPLAY INVISIBLE (-2450 1825);
FORCEPROP 1 LAST PIN_NAMES_ROTATE TRUE
J 2
(-2450 1825);
DISPLAY 0.489362 (-2450 1825);
PAINT GREEN (-2450 1825);
DISPLAY INVISIBLE (-2450 1825);
FORCEPROP 2 LAST VOLTAGE 6.3V
J 2
(-2800 1875);
DISPLAY 0.553191 (-2800 1875);
DISPLAY INVISIBLE (-2800 1875);
FORCEPROP 1 LAST MATERIAL X6S
J 2
(-2441 1904);
DISPLAY 0.574468 (-2441 1904);
PAINT GREEN (-2441 1904);
DISPLAY INVISIBLE (-2441 1904);
FORCEPROP 2 LAST PACK_TYPE C0201
J 2
(-2625 1875);
DISPLAY 0.553191 (-2625 1875);
DISPLAY INVISIBLE (-2625 1875);
FORCEPROP 2 LAST TOLERANCE 20%
J 2
(-2525 1875);
DISPLAY 0.553191 (-2525 1875);
DISPLAY INVISIBLE (-2525 1875);
FORCEPROP 1 LAST PATH I31
J 2
(-2450 1825);
DISPLAY 0.723404 (-2450 1825);
DISPLAY INVISIBLE (-2450 1825);
FORCEPROP 1 LAST PART_NUMBER SP_CH4221MEE01
J 2
(-2566 1913);
DISPLAY 0.574468 (-2566 1913);
PAINT GREEN (-2566 1913);
DISPLAY INVISIBLE (-2566 1913);
FORCEPROP 1 LAST LOCATION C6729
J 0
(-2200 1900);
DISPLAY 1.021277 (-2200 1900);
DISPLAY INVISIBLE (-2200 1900);
FORCEADD Q_CAP_DIFFBUS..2
R 2
(-2450 2025);
FORCEPROP 1 LAST LOCATION C6727
J 2
(-2150 2025);
DISPLAY 0.723404 (-2150 2025);
PAINT GREEN (-2150 2025);
FORCEPROP 2 LAST $SEC 1
J 2
(-2275 2100);
DISPLAY 0.680851 (-2275 2100);
PAINT MONO (-2275 2100);
DISPLAY INVISIBLE (-2275 2100);
FORCEPROP 2 LAST CDS_SEC 1
J 2
(-2275 2100);
DISPLAY 0.680851 (-2275 2100);
DISPLAY INVISIBLE (-2275 2100);
FORCEPROP 2 LASTPIN (-2375 2025) $PN 1
J 0
(-2365 2035);
DISPLAY 0.808511 (-2365 2035);
FORCEPROP 2 LASTPIN (-2525 2025) $PN 2
J 2
(-2535 2035);
DISPLAY 0.808511 (-2535 2035);
FORCEPROP 2 LAST VALUE DIFF BUS_0.22UF
J 2
(-2600 2025);
DISPLAY 0.553191 (-2600 2025);
FORCEPROP 1 LAST CDS_LMAN_SYM_OUTLINE -25,50,25,-50
J 2
(-2450 2025);
DISPLAY 0.468085 (-2450 2025);
PAINT GREEN (-2450 2025);
DISPLAY INVISIBLE (-2450 2025);
FORCEPROP 2 LAST CDS_LIB pure_quanta
J 2
(-2450 2025);
DISPLAY INVISIBLE (-2450 2025);
FORCEPROP 1 LAST PIN_NAMES_ROTATE TRUE
J 2
(-2450 2025);
DISPLAY 0.489362 (-2450 2025);
PAINT GREEN (-2450 2025);
DISPLAY INVISIBLE (-2450 2025);
FORCEPROP 2 LAST VOLTAGE 6.3V
J 2
(-2800 2075);
DISPLAY 0.553191 (-2800 2075);
DISPLAY INVISIBLE (-2800 2075);
FORCEPROP 1 LAST MATERIAL X6S
J 2
(-2441 2104);
DISPLAY 0.574468 (-2441 2104);
PAINT GREEN (-2441 2104);
DISPLAY INVISIBLE (-2441 2104);
FORCEPROP 2 LAST PACK_TYPE C0201
J 2
(-2625 2075);
DISPLAY 0.553191 (-2625 2075);
DISPLAY INVISIBLE (-2625 2075);
FORCEPROP 2 LAST TOLERANCE 20%
J 2
(-2525 2075);
DISPLAY 0.553191 (-2525 2075);
DISPLAY INVISIBLE (-2525 2075);
FORCEPROP 1 LAST PATH I32
J 2
(-2450 2025);
DISPLAY 0.723404 (-2450 2025);
DISPLAY INVISIBLE (-2450 2025);
FORCEPROP 1 LAST PART_NUMBER SP_CH4221MEE01
J 2
(-2566 2113);
DISPLAY 0.574468 (-2566 2113);
PAINT GREEN (-2566 2113);
DISPLAY INVISIBLE (-2566 2113);
FORCEPROP 1 LAST LOCATION C6727
J 0
(-2200 2100);
DISPLAY 1.021277 (-2200 2100);
DISPLAY INVISIBLE (-2200 2100);
FORCEADD TAP..1
(-1900 1025);
FORCEPROP 3 LASTPIN (-1950 1025) SIG_NAME P5E_CPU1_P3_TX_BUF_C_DP<6>
J 0
(-1940 1035);
DISPLAY 0.659574 (-1940 1035);
PAINT MONO (-1940 1035);
DISPLAY INVISIBLE (-1940 1035);
FORCEPROP 1 LASTPIN (-1950 1025) BN 6
J 0
(-1962 1033);
DISPLAY 0.680851 (-1962 1033);
PAINT GREEN (-1962 1033);
FORCEPROP 2 LAST CDS_LIB standard
J 0
(-1900 1025);
DISPLAY INVISIBLE (-1900 1025);
FORCEPROP 1 LAST BODY_TYPE PLUMBING
J 0
(-1900 1075);
DISPLAY 0.872340 (-1900 1075);
PAINT GREEN (-1900 1075);
DISPLAY INVISIBLE (-1900 1075);
FORCEPROP 1 LAST HDL_TAP TRUE
J 0
(-1575 900);
DISPLAY 0.872340 (-1575 900);
DISPLAY INVISIBLE (-1575 900);
FORCEPROP 1 LAST PATH I33
J 0
(-1902 1025);
DISPLAY 0.872340 (-1902 1025);
PAINT GREEN (-1902 1025);
DISPLAY INVISIBLE (-1902 1025);
FORCEADD TAP..1
(-1900 1225);
FORCEPROP 3 LASTPIN (-1950 1225) SIG_NAME P5E_CPU1_P3_TX_BUF_C_DP<5>
J 0
(-1940 1235);
DISPLAY 0.659574 (-1940 1235);
PAINT MONO (-1940 1235);
DISPLAY INVISIBLE (-1940 1235);
FORCEPROP 1 LASTPIN (-1950 1225) BN 5
J 0
(-1962 1233);
DISPLAY 0.680851 (-1962 1233);
PAINT GREEN (-1962 1233);
FORCEPROP 2 LAST CDS_LIB standard
J 0
(-1900 1225);
DISPLAY INVISIBLE (-1900 1225);
FORCEPROP 1 LAST BODY_TYPE PLUMBING
J 0
(-1900 1275);
DISPLAY 0.872340 (-1900 1275);
PAINT GREEN (-1900 1275);
DISPLAY INVISIBLE (-1900 1275);
FORCEPROP 1 LAST HDL_TAP TRUE
J 0
(-1575 1100);
DISPLAY 0.872340 (-1575 1100);
DISPLAY INVISIBLE (-1575 1100);
FORCEPROP 1 LAST PATH I34
J 0
(-1902 1225);
DISPLAY 0.872340 (-1902 1225);
PAINT GREEN (-1902 1225);
DISPLAY INVISIBLE (-1902 1225);
FORCEADD TAP..1
(-1700 1175);
FORCEPROP 3 LASTPIN (-1750 1175) SIG_NAME P5E_CPU1_P3_TX_BUF_C_DN<5>
J 0
(-1740 1185);
DISPLAY 0.659574 (-1740 1185);
PAINT MONO (-1740 1185);
DISPLAY INVISIBLE (-1740 1185);
FORCEPROP 1 LASTPIN (-1750 1175) BN 5
J 0
(-1762 1183);
DISPLAY 0.680851 (-1762 1183);
PAINT GREEN (-1762 1183);
FORCEPROP 2 LAST CDS_LIB standard
J 0
(-1700 1175);
DISPLAY INVISIBLE (-1700 1175);
FORCEPROP 1 LAST BODY_TYPE PLUMBING
J 0
(-1700 1225);
DISPLAY 0.872340 (-1700 1225);
PAINT GREEN (-1700 1225);
DISPLAY INVISIBLE (-1700 1225);
FORCEPROP 1 LAST HDL_TAP TRUE
J 0
(-1375 1050);
DISPLAY 0.872340 (-1375 1050);
DISPLAY INVISIBLE (-1375 1050);
FORCEPROP 1 LAST PATH I35
J 0
(-1702 1175);
DISPLAY 0.872340 (-1702 1175);
PAINT GREEN (-1702 1175);
DISPLAY INVISIBLE (-1702 1175);
FORCEADD TAP..1
(-1900 1425);
FORCEPROP 3 LASTPIN (-1950 1425) SIG_NAME P5E_CPU1_P3_TX_BUF_C_DP<4>
J 0
(-1940 1435);
DISPLAY 0.659574 (-1940 1435);
PAINT MONO (-1940 1435);
DISPLAY INVISIBLE (-1940 1435);
FORCEPROP 1 LASTPIN (-1950 1425) BN 4
J 0
(-1962 1433);
DISPLAY 0.680851 (-1962 1433);
PAINT GREEN (-1962 1433);
FORCEPROP 2 LAST CDS_LIB standard
J 0
(-1900 1425);
DISPLAY INVISIBLE (-1900 1425);
FORCEPROP 1 LAST BODY_TYPE PLUMBING
J 0
(-1900 1475);
DISPLAY 0.872340 (-1900 1475);
PAINT GREEN (-1900 1475);
DISPLAY INVISIBLE (-1900 1475);
FORCEPROP 1 LAST HDL_TAP TRUE
J 0
(-1575 1300);
DISPLAY 0.872340 (-1575 1300);
DISPLAY INVISIBLE (-1575 1300);
FORCEPROP 1 LAST PATH I36
J 0
(-1902 1425);
DISPLAY 0.872340 (-1902 1425);
PAINT GREEN (-1902 1425);
DISPLAY INVISIBLE (-1902 1425);
FORCEADD TAP..1
(-1700 1375);
FORCEPROP 3 LASTPIN (-1750 1375) SIG_NAME P5E_CPU1_P3_TX_BUF_C_DN<4>
J 0
(-1740 1385);
DISPLAY 0.659574 (-1740 1385);
PAINT MONO (-1740 1385);
DISPLAY INVISIBLE (-1740 1385);
FORCEPROP 1 LASTPIN (-1750 1375) BN 4
J 0
(-1762 1383);
DISPLAY 0.680851 (-1762 1383);
PAINT GREEN (-1762 1383);
FORCEPROP 2 LAST CDS_LIB standard
J 0
(-1700 1375);
DISPLAY INVISIBLE (-1700 1375);
FORCEPROP 1 LAST BODY_TYPE PLUMBING
J 0
(-1700 1425);
DISPLAY 0.872340 (-1700 1425);
PAINT GREEN (-1700 1425);
DISPLAY INVISIBLE (-1700 1425);
FORCEPROP 1 LAST HDL_TAP TRUE
J 0
(-1375 1250);
DISPLAY 0.872340 (-1375 1250);
DISPLAY INVISIBLE (-1375 1250);
FORCEPROP 1 LAST PATH I37
J 0
(-1702 1375);
DISPLAY 0.872340 (-1702 1375);
PAINT GREEN (-1702 1375);
DISPLAY INVISIBLE (-1702 1375);
FORCEADD TAP..1
(-1900 1625);
FORCEPROP 3 LASTPIN (-1950 1625) SIG_NAME P5E_CPU1_P3_TX_BUF_C_DP<3>
J 0
(-1940 1635);
DISPLAY 0.659574 (-1940 1635);
PAINT MONO (-1940 1635);
DISPLAY INVISIBLE (-1940 1635);
FORCEPROP 1 LASTPIN (-1950 1625) BN 3
J 0
(-1962 1633);
DISPLAY 0.680851 (-1962 1633);
PAINT GREEN (-1962 1633);
FORCEPROP 2 LAST CDS_LIB standard
J 0
(-1900 1625);
DISPLAY INVISIBLE (-1900 1625);
FORCEPROP 1 LAST BODY_TYPE PLUMBING
J 0
(-1900 1675);
DISPLAY 0.872340 (-1900 1675);
PAINT GREEN (-1900 1675);
DISPLAY INVISIBLE (-1900 1675);
FORCEPROP 1 LAST HDL_TAP TRUE
J 0
(-1575 1500);
DISPLAY 0.872340 (-1575 1500);
DISPLAY INVISIBLE (-1575 1500);
FORCEPROP 1 LAST PATH I38
J 0
(-1902 1625);
DISPLAY 0.872340 (-1902 1625);
PAINT GREEN (-1902 1625);
DISPLAY INVISIBLE (-1902 1625);
FORCEADD TAP..1
(-1700 1575);
FORCEPROP 3 LASTPIN (-1750 1575) SIG_NAME P5E_CPU1_P3_TX_BUF_C_DN<3>
J 0
(-1740 1585);
DISPLAY 0.659574 (-1740 1585);
PAINT MONO (-1740 1585);
DISPLAY INVISIBLE (-1740 1585);
FORCEPROP 1 LASTPIN (-1750 1575) BN 3
J 0
(-1762 1583);
DISPLAY 0.680851 (-1762 1583);
PAINT GREEN (-1762 1583);
FORCEPROP 2 LAST CDS_LIB standard
J 0
(-1700 1575);
DISPLAY INVISIBLE (-1700 1575);
FORCEPROP 1 LAST BODY_TYPE PLUMBING
J 0
(-1700 1625);
DISPLAY 0.872340 (-1700 1625);
PAINT GREEN (-1700 1625);
DISPLAY INVISIBLE (-1700 1625);
FORCEPROP 1 LAST HDL_TAP TRUE
J 0
(-1375 1450);
DISPLAY 0.872340 (-1375 1450);
DISPLAY INVISIBLE (-1375 1450);
FORCEPROP 1 LAST PATH I39
J 0
(-1702 1575);
DISPLAY 0.872340 (-1702 1575);
PAINT GREEN (-1702 1575);
DISPLAY INVISIBLE (-1702 1575);
FORCEADD TAP..1
R 2
(-3425 975);
FORCEPROP 3 LASTPIN (-3375 975) SIG_NAME P5E_CPU1_P3_TX_BUF_DN<6>
J 0
(-3365 985);
DISPLAY 0.659574 (-3365 985);
PAINT MONO (-3365 985);
DISPLAY INVISIBLE (-3365 985);
FORCEPROP 1 LASTPIN (-3375 975) BN 6
J 2
(-3363 983);
DISPLAY 0.680851 (-3363 983);
PAINT GREEN (-3363 983);
FORCEPROP 2 LAST CDS_LIB standard
J 0
(-3425 975);
DISPLAY INVISIBLE (-3425 975);
FORCEPROP 1 LAST BODY_TYPE PLUMBING
J 2
(-3425 1025);
DISPLAY 0.872340 (-3425 1025);
PAINT GREEN (-3425 1025);
DISPLAY INVISIBLE (-3425 1025);
FORCEPROP 1 LAST HDL_TAP TRUE
J 2
(-3750 850);
DISPLAY 0.872340 (-3750 850);
DISPLAY INVISIBLE (-3750 850);
FORCEPROP 1 LAST PATH I4
J 2
(-3423 975);
DISPLAY 0.872340 (-3423 975);
PAINT GREEN (-3423 975);
DISPLAY INVISIBLE (-3423 975);
FORCEADD TAP..1
(-1900 1825);
FORCEPROP 3 LASTPIN (-1950 1825) SIG_NAME P5E_CPU1_P3_TX_BUF_C_DP<2>
J 0
(-1940 1835);
DISPLAY 0.659574 (-1940 1835);
PAINT MONO (-1940 1835);
DISPLAY INVISIBLE (-1940 1835);
FORCEPROP 1 LASTPIN (-1950 1825) BN 2
J 0
(-1962 1833);
DISPLAY 0.680851 (-1962 1833);
PAINT GREEN (-1962 1833);
FORCEPROP 2 LAST CDS_LIB standard
J 0
(-1900 1825);
DISPLAY INVISIBLE (-1900 1825);
FORCEPROP 1 LAST BODY_TYPE PLUMBING
J 0
(-1900 1875);
DISPLAY 0.872340 (-1900 1875);
PAINT GREEN (-1900 1875);
DISPLAY INVISIBLE (-1900 1875);
FORCEPROP 1 LAST HDL_TAP TRUE
J 0
(-1575 1700);
DISPLAY 0.872340 (-1575 1700);
DISPLAY INVISIBLE (-1575 1700);
FORCEPROP 1 LAST PATH I40
J 0
(-1902 1825);
DISPLAY 0.872340 (-1902 1825);
PAINT GREEN (-1902 1825);
DISPLAY INVISIBLE (-1902 1825);
FORCEADD TAP..1
(-1700 1975);
FORCEPROP 3 LASTPIN (-1750 1975) SIG_NAME P5E_CPU1_P3_TX_BUF_C_DN<1>
J 0
(-1740 1985);
DISPLAY 0.659574 (-1740 1985);
PAINT MONO (-1740 1985);
DISPLAY INVISIBLE (-1740 1985);
FORCEPROP 1 LASTPIN (-1750 1975) BN 1
J 0
(-1762 1983);
DISPLAY 0.680851 (-1762 1983);
PAINT GREEN (-1762 1983);
FORCEPROP 2 LAST CDS_LIB standard
J 0
(-1700 1975);
DISPLAY INVISIBLE (-1700 1975);
FORCEPROP 1 LAST BODY_TYPE PLUMBING
J 0
(-1700 2025);
DISPLAY 0.872340 (-1700 2025);
PAINT GREEN (-1700 2025);
DISPLAY INVISIBLE (-1700 2025);
FORCEPROP 1 LAST HDL_TAP TRUE
J 0
(-1375 1850);
DISPLAY 0.872340 (-1375 1850);
DISPLAY INVISIBLE (-1375 1850);
FORCEPROP 1 LAST PATH I41
J 0
(-1702 1975);
DISPLAY 0.872340 (-1702 1975);
PAINT GREEN (-1702 1975);
DISPLAY INVISIBLE (-1702 1975);
FORCEADD TAP..1
(-1700 1775);
FORCEPROP 3 LASTPIN (-1750 1775) SIG_NAME P5E_CPU1_P3_TX_BUF_C_DN<2>
J 0
(-1740 1785);
DISPLAY 0.659574 (-1740 1785);
PAINT MONO (-1740 1785);
DISPLAY INVISIBLE (-1740 1785);
FORCEPROP 1 LASTPIN (-1750 1775) BN 2
J 0
(-1762 1783);
DISPLAY 0.680851 (-1762 1783);
PAINT GREEN (-1762 1783);
FORCEPROP 2 LAST CDS_LIB standard
J 0
(-1700 1775);
DISPLAY INVISIBLE (-1700 1775);
FORCEPROP 1 LAST BODY_TYPE PLUMBING
J 0
(-1700 1825);
DISPLAY 0.872340 (-1700 1825);
PAINT GREEN (-1700 1825);
DISPLAY INVISIBLE (-1700 1825);
FORCEPROP 1 LAST HDL_TAP TRUE
J 0
(-1375 1650);
DISPLAY 0.872340 (-1375 1650);
DISPLAY INVISIBLE (-1375 1650);
FORCEPROP 1 LAST PATH I42
J 0
(-1702 1775);
DISPLAY 0.872340 (-1702 1775);
PAINT GREEN (-1702 1775);
DISPLAY INVISIBLE (-1702 1775);
FORCEADD TAP..1
R 2
(-3425 2175);
FORCEPROP 3 LASTPIN (-3375 2175) SIG_NAME P5E_CPU1_P3_TX_BUF_DN<0>
J 0
(-3365 2185);
DISPLAY 0.659574 (-3365 2185);
PAINT MONO (-3365 2185);
DISPLAY INVISIBLE (-3365 2185);
FORCEPROP 1 LASTPIN (-3375 2175) BN 0
J 2
(-3363 2183);
DISPLAY 0.680851 (-3363 2183);
PAINT GREEN (-3363 2183);
FORCEPROP 2 LAST CDS_LIB standard
J 0
(-3425 2175);
DISPLAY INVISIBLE (-3425 2175);
FORCEPROP 1 LAST BODY_TYPE PLUMBING
J 2
(-3425 2225);
DISPLAY 0.872340 (-3425 2225);
PAINT GREEN (-3425 2225);
DISPLAY INVISIBLE (-3425 2225);
FORCEPROP 1 LAST HDL_TAP TRUE
J 2
(-3750 2050);
DISPLAY 0.872340 (-3750 2050);
DISPLAY INVISIBLE (-3750 2050);
FORCEPROP 1 LAST PATH I43
J 2
(-3423 2175);
DISPLAY 0.872340 (-3423 2175);
PAINT GREEN (-3423 2175);
DISPLAY INVISIBLE (-3423 2175);
FORCEADD TAP..1
R 2
(-3175 2025);
FORCEPROP 3 LASTPIN (-3125 2025) SIG_NAME P5E_CPU1_P3_TX_BUF_DP<1>
J 0
(-3115 2035);
DISPLAY 0.659574 (-3115 2035);
PAINT MONO (-3115 2035);
DISPLAY INVISIBLE (-3115 2035);
FORCEPROP 1 LASTPIN (-3125 2025) BN 1
J 2
(-3113 2033);
DISPLAY 0.680851 (-3113 2033);
PAINT GREEN (-3113 2033);
FORCEPROP 2 LAST CDS_LIB standard
J 0
(-3175 2025);
DISPLAY INVISIBLE (-3175 2025);
FORCEPROP 1 LAST BODY_TYPE PLUMBING
J 2
(-3175 2075);
DISPLAY 0.872340 (-3175 2075);
PAINT GREEN (-3175 2075);
DISPLAY INVISIBLE (-3175 2075);
FORCEPROP 1 LAST HDL_TAP TRUE
J 2
(-3500 1900);
DISPLAY 0.872340 (-3500 1900);
DISPLAY INVISIBLE (-3500 1900);
FORCEPROP 1 LAST PATH I44
J 2
(-3173 2025);
DISPLAY 0.872340 (-3173 2025);
PAINT GREEN (-3173 2025);
DISPLAY INVISIBLE (-3173 2025);
FORCEADD TAP..1
R 2
(-3175 2225);
FORCEPROP 3 LASTPIN (-3125 2225) SIG_NAME P5E_CPU1_P3_TX_BUF_DP<0>
J 0
(-3115 2235);
DISPLAY 0.659574 (-3115 2235);
PAINT MONO (-3115 2235);
DISPLAY INVISIBLE (-3115 2235);
FORCEPROP 1 LASTPIN (-3125 2225) BN 0
J 2
(-3113 2233);
DISPLAY 0.680851 (-3113 2233);
PAINT GREEN (-3113 2233);
FORCEPROP 2 LAST CDS_LIB standard
J 0
(-3175 2225);
DISPLAY INVISIBLE (-3175 2225);
FORCEPROP 1 LAST BODY_TYPE PLUMBING
J 2
(-3175 2275);
DISPLAY 0.872340 (-3175 2275);
PAINT GREEN (-3175 2275);
DISPLAY INVISIBLE (-3175 2275);
FORCEPROP 1 LAST HDL_TAP TRUE
J 2
(-3500 2100);
DISPLAY 0.872340 (-3500 2100);
DISPLAY INVISIBLE (-3500 2100);
FORCEPROP 1 LAST PATH I45
J 2
(-3173 2225);
DISPLAY 0.872340 (-3173 2225);
PAINT GREEN (-3173 2225);
DISPLAY INVISIBLE (-3173 2225);
FORCEADD PT5161LRS..10
(-7775 4525);
FORCEPROP 1 LAST LOCATION U6017
J 0
(-8125 6150);
DISPLAY 0.723404 (-8125 6150);
PAINT GREEN (-8125 6150);
FORCEPROP 0 LAST $SEC 10
J 0
(-8125 6300);
DISPLAY 0.680851 (-8125 6300);
PAINT MONO (-8125 6300);
DISPLAY INVISIBLE (-8125 6300);
FORCEPROP 0 LAST CDS_SEC 10
J 0
(-8125 6300);
DISPLAY 0.680851 (-8125 6300);
DISPLAY INVISIBLE (-8125 6300);
FORCEPROP 0 LASTPIN (-7325 5675) $PN P10
J 0
(-7315 5685);
DISPLAY 0.680851 (-7315 5685);
PAINT MONO (-7315 5685);
FORCEPROP 0 LASTPIN (-7325 5325) $PN AA10
J 0
(-7315 5335);
DISPLAY 0.680851 (-7315 5335);
PAINT MONO (-7315 5335);
FORCEPROP 0 LASTPIN (-7325 4975) $PN AH10
J 0
(-7315 4985);
DISPLAY 0.680851 (-7315 4985);
PAINT MONO (-7315 4985);
FORCEPROP 0 LASTPIN (-7325 4625) $PN AR10
J 0
(-7315 4635);
DISPLAY 0.680851 (-7315 4635);
PAINT MONO (-7315 4635);
FORCEPROP 0 LASTPIN (-7325 4275) $PN BB10
J 0
(-7315 4285);
DISPLAY 0.680851 (-7315 4285);
PAINT MONO (-7315 4285);
FORCEPROP 0 LASTPIN (-7325 3925) $PN BJ10
J 0
(-7315 3935);
DISPLAY 0.680851 (-7315 3935);
PAINT MONO (-7315 3935);
FORCEPROP 0 LASTPIN (-7325 3575) $PN BT10
J 0
(-7315 3585);
DISPLAY 0.680851 (-7315 3585);
PAINT MONO (-7315 3585);
FORCEPROP 0 LASTPIN (-7325 3225) $PN CC10
J 0
(-7315 3235);
DISPLAY 0.680851 (-7315 3235);
PAINT MONO (-7315 3235);
FORCEPROP 0 LASTPIN (-7325 5775) $PN M7
J 0
(-7315 5785);
DISPLAY 0.680851 (-7315 5785);
PAINT MONO (-7315 5785);
FORCEPROP 0 LASTPIN (-7325 5425) $PN W7
J 0
(-7315 5435);
DISPLAY 0.680851 (-7315 5435);
PAINT MONO (-7315 5435);
FORCEPROP 0 LASTPIN (-7325 5075) $PN AF7
J 0
(-7315 5085);
DISPLAY 0.680851 (-7315 5085);
PAINT MONO (-7315 5085);
FORCEPROP 0 LASTPIN (-7325 4725) $PN AN7
J 0
(-7315 4735);
DISPLAY 0.680851 (-7315 4735);
PAINT MONO (-7315 4735);
FORCEPROP 0 LASTPIN (-7325 4375) $PN AY7
J 0
(-7315 4385);
DISPLAY 0.680851 (-7315 4385);
PAINT MONO (-7315 4385);
FORCEPROP 0 LASTPIN (-7325 4025) $PN BG7
J 0
(-7315 4035);
DISPLAY 0.680851 (-7315 4035);
PAINT MONO (-7315 4035);
FORCEPROP 0 LASTPIN (-7325 3675) $PN BP7
J 0
(-7315 3685);
DISPLAY 0.680851 (-7315 3685);
PAINT MONO (-7315 3685);
FORCEPROP 0 LASTPIN (-7325 3325) $PN CA7
J 0
(-7315 3335);
DISPLAY 0.680851 (-7315 3335);
PAINT MONO (-7315 3335);
FORCEPROP 1 LAST MATERIAL IC
J 0
(-8125 6000);
DISPLAY 0.723404 (-8125 6000);
PAINT GREEN (-8125 6000);
FORCEPROP 2 LAST VALUE PT5161LRS
J 0
(-8125 6200);
DISPLAY 0.680851 (-8125 6200);
FORCEPROP 2 LAST PART_TYPE SMLF
J 0
(-8125 6250);
DISPLAY 0.680851 (-8125 6250);
FORCEPROP 2 LAST CDS_LIB pure_quanta
J 0
(-7775 4525);
DISPLAY INVISIBLE (-7775 4525);
FORCEPROP 1 LAST CDS_LMAN_SYM_OUTLINE -350,1450,300,-1400
J 0
(-7775 4525);
DISPLAY 0.468085 (-7775 4525);
PAINT GREEN (-7775 4525);
DISPLAY INVISIBLE (-7775 4525);
FORCEPROP 1 LAST NEEDS_NO_SIZE TRUE
J 0
(-7775 4525);
DISPLAY 0.723404 (-7775 4525);
PAINT GREEN (-7775 4525);
DISPLAY INVISIBLE (-7775 4525);
FORCEPROP 1 LAST PATH I46
J 0
(-7775 4525);
DISPLAY 0.723404 (-7775 4525);
PAINT GREEN (-7775 4525);
DISPLAY INVISIBLE (-7775 4525);
FORCEPROP 1 LAST PART_NUMBER AJ051610U03
J 0
(-8125 6075);
DISPLAY 0.723404 (-8125 6075);
PAINT GREEN (-8125 6075);
DISPLAY INVISIBLE (-8125 6075);
FORCEADD Q_CAP_DIFFBUS..2
R 2
(-2450 2175);
FORCEPROP 1 LAST LOCATION C6726
J 2
(-2150 2175);
DISPLAY 0.723404 (-2150 2175);
PAINT GREEN (-2150 2175);
FORCEPROP 2 LAST $SEC 1
J 2
(-2275 2250);
DISPLAY 0.680851 (-2275 2250);
PAINT MONO (-2275 2250);
DISPLAY INVISIBLE (-2275 2250);
FORCEPROP 2 LAST CDS_SEC 1
J 2
(-2275 2250);
DISPLAY 0.680851 (-2275 2250);
DISPLAY INVISIBLE (-2275 2250);
FORCEPROP 2 LASTPIN (-2375 2175) $PN 1
J 0
(-2365 2185);
DISPLAY 0.808511 (-2365 2185);
FORCEPROP 2 LASTPIN (-2525 2175) $PN 2
J 2
(-2535 2185);
DISPLAY 0.808511 (-2535 2185);
FORCEPROP 2 LAST VALUE DIFF BUS_0.22UF
J 2
(-2600 2175);
DISPLAY 0.553191 (-2600 2175);
FORCEPROP 1 LAST CDS_LMAN_SYM_OUTLINE -25,50,25,-50
J 2
(-2450 2175);
DISPLAY 0.468085 (-2450 2175);
PAINT GREEN (-2450 2175);
DISPLAY INVISIBLE (-2450 2175);
FORCEPROP 2 LAST CDS_LIB pure_quanta
J 2
(-2450 2175);
DISPLAY INVISIBLE (-2450 2175);
FORCEPROP 1 LAST PIN_NAMES_ROTATE TRUE
J 2
(-2450 2175);
DISPLAY 0.489362 (-2450 2175);
PAINT GREEN (-2450 2175);
DISPLAY INVISIBLE (-2450 2175);
FORCEPROP 2 LAST VOLTAGE 6.3V
J 2
(-2800 2225);
DISPLAY 0.553191 (-2800 2225);
DISPLAY INVISIBLE (-2800 2225);
FORCEPROP 1 LAST MATERIAL X6S
J 2
(-2441 2254);
DISPLAY 0.574468 (-2441 2254);
PAINT GREEN (-2441 2254);
DISPLAY INVISIBLE (-2441 2254);
FORCEPROP 2 LAST PACK_TYPE C0201
J 2
(-2625 2225);
DISPLAY 0.553191 (-2625 2225);
DISPLAY INVISIBLE (-2625 2225);
FORCEPROP 2 LAST TOLERANCE 20%
J 2
(-2525 2225);
DISPLAY 0.553191 (-2525 2225);
DISPLAY INVISIBLE (-2525 2225);
FORCEPROP 1 LAST PATH I47
J 2
(-2450 2175);
DISPLAY 0.723404 (-2450 2175);
DISPLAY INVISIBLE (-2450 2175);
FORCEPROP 1 LAST PART_NUMBER SP_CH4221MEE01
J 2
(-2566 2263);
DISPLAY 0.574468 (-2566 2263);
PAINT GREEN (-2566 2263);
DISPLAY INVISIBLE (-2566 2263);
FORCEPROP 1 LAST LOCATION C6726
J 0
(-2200 2250);
DISPLAY 1.021277 (-2200 2250);
DISPLAY INVISIBLE (-2200 2250);
FORCEADD Q_CAP_DIFFBUS..2
R 2
(-2450 2225);
FORCEPROP 1 LAST LOCATION C6725
J 2
(-2150 2225);
DISPLAY 0.723404 (-2150 2225);
PAINT GREEN (-2150 2225);
FORCEPROP 2 LAST $SEC 1
J 2
(-2275 2300);
DISPLAY 0.680851 (-2275 2300);
PAINT MONO (-2275 2300);
DISPLAY INVISIBLE (-2275 2300);
FORCEPROP 2 LAST CDS_SEC 1
J 2
(-2275 2300);
DISPLAY 0.680851 (-2275 2300);
DISPLAY INVISIBLE (-2275 2300);
FORCEPROP 2 LASTPIN (-2375 2225) $PN 1
J 0
(-2365 2235);
DISPLAY 0.808511 (-2365 2235);
FORCEPROP 2 LASTPIN (-2525 2225) $PN 2
J 2
(-2535 2235);
DISPLAY 0.808511 (-2535 2235);
FORCEPROP 2 LAST VALUE DIFF BUS_0.22UF
J 2
(-2600 2225);
DISPLAY 0.553191 (-2600 2225);
FORCEPROP 2 LAST PACK_TYPE C0201
J 2
(-2500 2375);
DISPLAY 0.553191 (-2500 2375);
PAINT GREEN (-2500 2375);
FORCEPROP 2 LAST TOLERANCE 20%
J 2
(-2400 2375);
DISPLAY 0.553191 (-2400 2375);
PAINT GREEN (-2400 2375);
FORCEPROP 1 LAST MATERIAL X6S
J 2
(-2541 2429);
DISPLAY 0.574468 (-2541 2429);
PAINT GREEN (-2541 2429);
FORCEPROP 2 LAST VOLTAGE 6.3V
J 2
(-2275 2375);
DISPLAY 0.553191 (-2275 2375);
PAINT GREEN (-2275 2375);
FORCEPROP 2 LAST CDS_LIB pure_quanta
J 2
(-2450 2225);
DISPLAY INVISIBLE (-2450 2225);
FORCEPROP 1 LAST CDS_LMAN_SYM_OUTLINE -25,50,25,-50
J 2
(-2450 2225);
DISPLAY 0.468085 (-2450 2225);
PAINT GREEN (-2450 2225);
DISPLAY INVISIBLE (-2450 2225);
FORCEPROP 1 LAST PIN_NAMES_ROTATE TRUE
J 2
(-2450 2225);
DISPLAY 0.489362 (-2450 2225);
PAINT GREEN (-2450 2225);
DISPLAY INVISIBLE (-2450 2225);
FORCEPROP 1 LAST PATH I48
J 2
(-2450 2225);
DISPLAY 0.723404 (-2450 2225);
DISPLAY INVISIBLE (-2450 2225);
FORCEPROP 1 LAST PART_NUMBER SP_CH4221MEE01
J 2
(-2266 2313);
DISPLAY 0.574468 (-2266 2313);
PAINT GREEN (-2266 2313);
DISPLAY INVISIBLE (-2266 2313);
FORCEPROP 1 LAST LOCATION C6725
J 0
(-2200 2300);
DISPLAY 1.021277 (-2200 2300);
DISPLAY INVISIBLE (-2200 2300);
FORCEADD TAP..1
(-1900 2025);
FORCEPROP 3 LASTPIN (-1950 2025) SIG_NAME P5E_CPU1_P3_TX_BUF_C_DP<1>
J 0
(-1940 2035);
DISPLAY 0.659574 (-1940 2035);
PAINT MONO (-1940 2035);
DISPLAY INVISIBLE (-1940 2035);
FORCEPROP 1 LASTPIN (-1950 2025) BN 1
J 0
(-1962 2033);
DISPLAY 0.680851 (-1962 2033);
PAINT GREEN (-1962 2033);
FORCEPROP 2 LAST CDS_LIB standard
J 0
(-1900 2025);
DISPLAY INVISIBLE (-1900 2025);
FORCEPROP 1 LAST BODY_TYPE PLUMBING
J 0
(-1900 2075);
DISPLAY 0.872340 (-1900 2075);
PAINT GREEN (-1900 2075);
DISPLAY INVISIBLE (-1900 2075);
FORCEPROP 1 LAST HDL_TAP TRUE
J 0
(-1575 1900);
DISPLAY 0.872340 (-1575 1900);
DISPLAY INVISIBLE (-1575 1900);
FORCEPROP 1 LAST PATH I49
J 0
(-1902 2025);
DISPLAY 0.872340 (-1902 2025);
PAINT GREEN (-1902 2025);
DISPLAY INVISIBLE (-1902 2025);
FORCEADD TAP..1
R 2
(-3175 825);
FORCEPROP 3 LASTPIN (-3125 825) SIG_NAME P5E_CPU1_P3_TX_BUF_DP<7>
J 0
(-3115 835);
DISPLAY 0.659574 (-3115 835);
PAINT MONO (-3115 835);
DISPLAY INVISIBLE (-3115 835);
FORCEPROP 1 LASTPIN (-3125 825) BN 7
J 2
(-3113 833);
DISPLAY 0.680851 (-3113 833);
PAINT GREEN (-3113 833);
FORCEPROP 2 LAST CDS_LIB standard
J 0
(-3175 825);
DISPLAY INVISIBLE (-3175 825);
FORCEPROP 1 LAST BODY_TYPE PLUMBING
J 2
(-3175 875);
DISPLAY 0.872340 (-3175 875);
PAINT GREEN (-3175 875);
DISPLAY INVISIBLE (-3175 875);
FORCEPROP 1 LAST HDL_TAP TRUE
J 2
(-3500 700);
DISPLAY 0.872340 (-3500 700);
DISPLAY INVISIBLE (-3500 700);
FORCEPROP 1 LAST PATH I5
J 2
(-3173 825);
DISPLAY 0.872340 (-3173 825);
PAINT GREEN (-3173 825);
DISPLAY INVISIBLE (-3173 825);
FORCEADD TAP..1
(-1900 2225);
FORCEPROP 3 LASTPIN (-1950 2225) SIG_NAME P5E_CPU1_P3_TX_BUF_C_DP<0>
J 0
(-1940 2235);
DISPLAY 0.659574 (-1940 2235);
PAINT MONO (-1940 2235);
DISPLAY INVISIBLE (-1940 2235);
FORCEPROP 1 LASTPIN (-1950 2225) BN 0
J 0
(-1962 2233);
DISPLAY 0.680851 (-1962 2233);
PAINT GREEN (-1962 2233);
FORCEPROP 2 LAST CDS_LIB standard
J 0
(-1900 2225);
DISPLAY INVISIBLE (-1900 2225);
FORCEPROP 1 LAST BODY_TYPE PLUMBING
J 0
(-1900 2275);
DISPLAY 0.872340 (-1900 2275);
PAINT GREEN (-1900 2275);
DISPLAY INVISIBLE (-1900 2275);
FORCEPROP 1 LAST HDL_TAP TRUE
J 0
(-1575 2100);
DISPLAY 0.872340 (-1575 2100);
DISPLAY INVISIBLE (-1575 2100);
FORCEPROP 1 LAST PATH I50
J 0
(-1902 2225);
DISPLAY 0.872340 (-1902 2225);
PAINT GREEN (-1902 2225);
DISPLAY INVISIBLE (-1902 2225);
FORCEADD TAP..1
(-1700 2175);
FORCEPROP 3 LASTPIN (-1750 2175) SIG_NAME P5E_CPU1_P3_TX_BUF_C_DN<0>
J 0
(-1740 2185);
DISPLAY 0.659574 (-1740 2185);
PAINT MONO (-1740 2185);
DISPLAY INVISIBLE (-1740 2185);
FORCEPROP 1 LASTPIN (-1750 2175) BN 0
J 0
(-1762 2183);
DISPLAY 0.680851 (-1762 2183);
PAINT GREEN (-1762 2183);
FORCEPROP 2 LAST CDS_LIB standard
J 0
(-1700 2175);
DISPLAY INVISIBLE (-1700 2175);
FORCEPROP 1 LAST BODY_TYPE PLUMBING
J 0
(-1700 2225);
DISPLAY 0.872340 (-1700 2225);
PAINT GREEN (-1700 2225);
DISPLAY INVISIBLE (-1700 2225);
FORCEPROP 1 LAST HDL_TAP TRUE
J 0
(-1375 2050);
DISPLAY 0.872340 (-1375 2050);
DISPLAY INVISIBLE (-1375 2050);
FORCEPROP 1 LAST PATH I51
J 0
(-1702 2175);
DISPLAY 0.872340 (-1702 2175);
PAINT GREEN (-1702 2175);
DISPLAY INVISIBLE (-1702 2175);
FORCEADD TAP..1
(-7050 3325);
FORCEPROP 3 LASTPIN (-7100 3325) SIG_NAME P5E_CPU1_P3_TX_BUF_DP<8>
J 0
(-7090 3335);
DISPLAY 0.659574 (-7090 3335);
PAINT MONO (-7090 3335);
DISPLAY INVISIBLE (-7090 3335);
FORCEPROP 1 LASTPIN (-7100 3325) BN 8
J 0
(-7112 3333);
DISPLAY 0.680851 (-7112 3333);
PAINT GREEN (-7112 3333);
FORCEPROP 2 LAST CDS_LIB standard
J 0
(-7050 3325);
DISPLAY INVISIBLE (-7050 3325);
FORCEPROP 1 LAST BODY_TYPE PLUMBING
J 0
(-7050 3375);
DISPLAY 0.872340 (-7050 3375);
PAINT GREEN (-7050 3375);
DISPLAY INVISIBLE (-7050 3375);
FORCEPROP 1 LAST HDL_TAP TRUE
J 0
(-6725 3200);
DISPLAY 0.872340 (-6725 3200);
DISPLAY INVISIBLE (-6725 3200);
FORCEPROP 1 LAST PATH I52
J 0
(-7052 3325);
DISPLAY 0.872340 (-7052 3325);
PAINT GREEN (-7052 3325);
DISPLAY INVISIBLE (-7052 3325);
FORCEADD TAP..1
(-6850 3225);
FORCEPROP 3 LASTPIN (-6900 3225) SIG_NAME P5E_CPU1_P3_TX_BUF_DN<8>
J 0
(-6890 3235);
DISPLAY 0.659574 (-6890 3235);
PAINT MONO (-6890 3235);
DISPLAY INVISIBLE (-6890 3235);
FORCEPROP 1 LASTPIN (-6900 3225) BN 8
J 0
(-6912 3233);
DISPLAY 0.680851 (-6912 3233);
PAINT GREEN (-6912 3233);
FORCEPROP 2 LAST CDS_LIB standard
J 0
(-6850 3225);
DISPLAY INVISIBLE (-6850 3225);
FORCEPROP 1 LAST BODY_TYPE PLUMBING
J 0
(-6850 3275);
DISPLAY 0.872340 (-6850 3275);
PAINT GREEN (-6850 3275);
DISPLAY INVISIBLE (-6850 3275);
FORCEPROP 1 LAST HDL_TAP TRUE
J 0
(-6525 3100);
DISPLAY 0.872340 (-6525 3100);
DISPLAY INVISIBLE (-6525 3100);
FORCEPROP 1 LAST PATH I53
J 0
(-6852 3225);
DISPLAY 0.872340 (-6852 3225);
PAINT GREEN (-6852 3225);
DISPLAY INVISIBLE (-6852 3225);
FORCEADD TAP..1
(-7050 3675);
FORCEPROP 3 LASTPIN (-7100 3675) SIG_NAME P5E_CPU1_P3_TX_BUF_DP<9>
J 0
(-7090 3685);
DISPLAY 0.659574 (-7090 3685);
PAINT MONO (-7090 3685);
DISPLAY INVISIBLE (-7090 3685);
FORCEPROP 1 LASTPIN (-7100 3675) BN 9
J 0
(-7112 3683);
DISPLAY 0.680851 (-7112 3683);
PAINT GREEN (-7112 3683);
FORCEPROP 2 LAST CDS_LIB standard
J 0
(-7050 3675);
DISPLAY INVISIBLE (-7050 3675);
FORCEPROP 1 LAST BODY_TYPE PLUMBING
J 0
(-7050 3725);
DISPLAY 0.872340 (-7050 3725);
PAINT GREEN (-7050 3725);
DISPLAY INVISIBLE (-7050 3725);
FORCEPROP 1 LAST HDL_TAP TRUE
J 0
(-6725 3550);
DISPLAY 0.872340 (-6725 3550);
DISPLAY INVISIBLE (-6725 3550);
FORCEPROP 1 LAST PATH I54
J 0
(-7052 3675);
DISPLAY 0.872340 (-7052 3675);
PAINT GREEN (-7052 3675);
DISPLAY INVISIBLE (-7052 3675);
FORCEADD TAP..1
(-6850 3575);
FORCEPROP 3 LASTPIN (-6900 3575) SIG_NAME P5E_CPU1_P3_TX_BUF_DN<9>
J 0
(-6890 3585);
DISPLAY 0.659574 (-6890 3585);
PAINT MONO (-6890 3585);
DISPLAY INVISIBLE (-6890 3585);
FORCEPROP 1 LASTPIN (-6900 3575) BN 9
J 0
(-6912 3583);
DISPLAY 0.680851 (-6912 3583);
PAINT GREEN (-6912 3583);
FORCEPROP 2 LAST CDS_LIB standard
J 0
(-6850 3575);
DISPLAY INVISIBLE (-6850 3575);
FORCEPROP 1 LAST BODY_TYPE PLUMBING
J 0
(-6850 3625);
DISPLAY 0.872340 (-6850 3625);
PAINT GREEN (-6850 3625);
DISPLAY INVISIBLE (-6850 3625);
FORCEPROP 1 LAST HDL_TAP TRUE
J 0
(-6525 3450);
DISPLAY 0.872340 (-6525 3450);
DISPLAY INVISIBLE (-6525 3450);
FORCEPROP 1 LAST PATH I55
J 0
(-6852 3575);
DISPLAY 0.872340 (-6852 3575);
PAINT GREEN (-6852 3575);
DISPLAY INVISIBLE (-6852 3575);
FORCEADD TAP..1
(-6850 3925);
FORCEPROP 3 LASTPIN (-6900 3925) SIG_NAME P5E_CPU1_P3_TX_BUF_DN<10>
J 0
(-6890 3935);
DISPLAY 0.659574 (-6890 3935);
PAINT MONO (-6890 3935);
DISPLAY INVISIBLE (-6890 3935);
FORCEPROP 1 LASTPIN (-6900 3925) BN 10
J 0
(-6912 3933);
DISPLAY 0.680851 (-6912 3933);
PAINT GREEN (-6912 3933);
FORCEPROP 2 LAST CDS_LIB standard
J 0
(-6850 3925);
DISPLAY INVISIBLE (-6850 3925);
FORCEPROP 1 LAST BODY_TYPE PLUMBING
J 0
(-6850 3975);
DISPLAY 0.872340 (-6850 3975);
PAINT GREEN (-6850 3975);
DISPLAY INVISIBLE (-6850 3975);
FORCEPROP 1 LAST HDL_TAP TRUE
J 0
(-6525 3800);
DISPLAY 0.872340 (-6525 3800);
DISPLAY INVISIBLE (-6525 3800);
FORCEPROP 1 LAST PATH I56
J 0
(-6852 3925);
DISPLAY 0.872340 (-6852 3925);
PAINT GREEN (-6852 3925);
DISPLAY INVISIBLE (-6852 3925);
FORCEADD OFFPAGE..2
(-700 2200);
FORCEPROP 2 LAST $XR0 120 
J 0
(-511 2200);
DISPLAY 0.638298 (-511 2200);
PAINT MONO (-511 2200);
FORCEPROP 2 LAST CDS_LIB standard
J 0
(-700 2200);
DISPLAY INVISIBLE (-700 2200);
FORCEPROP 1 LAST OFFPAGE TRUE
J 0
(-375 2075);
DISPLAY 0.872340 (-375 2075);
DISPLAY INVISIBLE (-375 2075);
FORCEPROP 1 LAST COMMENT_BODY TRUE
J 0
(-745 2105);
DISPLAY 0.872340 (-745 2105);
PAINT GREEN (-745 2105);
DISPLAY INVISIBLE (-745 2105);
FORCEPROP 2 LAST PATH I57
J 0
(-500 2250);
DISPLAY 0.680851 (-500 2250);
DISPLAY INVISIBLE (-500 2250);
FORCEADD OFFPAGE..2
(-700 2250);
FORCEPROP 2 LAST $XR0 120 
J 0
(-511 2250);
DISPLAY 0.638298 (-511 2250);
PAINT MONO (-511 2250);
FORCEPROP 2 LAST CDS_LIB standard
J 0
(-700 2250);
DISPLAY INVISIBLE (-700 2250);
FORCEPROP 1 LAST OFFPAGE TRUE
J 0
(-375 2125);
DISPLAY 0.872340 (-375 2125);
DISPLAY INVISIBLE (-375 2125);
FORCEPROP 1 LAST COMMENT_BODY TRUE
J 0
(-745 2155);
DISPLAY 0.872340 (-745 2155);
PAINT GREEN (-745 2155);
DISPLAY INVISIBLE (-745 2155);
FORCEPROP 2 LAST PATH I58
J 0
(-500 2300);
DISPLAY 0.680851 (-500 2300);
DISPLAY INVISIBLE (-500 2300);
FORCEADD OFFPAGE..1
(-8950 2075);
FORCEPROP 2 LAST $XR0 353 
J 0
(-9232 2075);
DISPLAY 0.638298 (-9232 2075);
PAINT MONO (-9232 2075);
FORCEPROP 2 LAST CDS_LIB standard
J 0
(-8950 2075);
DISPLAY INVISIBLE (-8950 2075);
FORCEPROP 1 LAST OFFPAGE TRUE
J 0
(-8625 1950);
DISPLAY 0.872340 (-8625 1950);
DISPLAY INVISIBLE (-8625 1950);
FORCEPROP 1 LAST COMMENT_BODY TRUE
J 0
(-8825 1975);
DISPLAY 0.872340 (-8825 1975);
PAINT GREEN (-8825 1975);
DISPLAY INVISIBLE (-8825 1975);
FORCEPROP 2 LAST PATH I59
J 0
(-9200 2125);
DISPLAY 0.680851 (-9200 2125);
DISPLAY INVISIBLE (-9200 2125);
FORCEADD TAP..1
R 2
(-3425 1175);
FORCEPROP 3 LASTPIN (-3375 1175) SIG_NAME P5E_CPU1_P3_TX_BUF_DN<5>
J 0
(-3365 1185);
DISPLAY 0.659574 (-3365 1185);
PAINT MONO (-3365 1185);
DISPLAY INVISIBLE (-3365 1185);
FORCEPROP 1 LASTPIN (-3375 1175) BN 5
J 2
(-3363 1183);
DISPLAY 0.680851 (-3363 1183);
PAINT GREEN (-3363 1183);
FORCEPROP 2 LAST CDS_LIB standard
J 0
(-3425 1175);
DISPLAY INVISIBLE (-3425 1175);
FORCEPROP 1 LAST BODY_TYPE PLUMBING
J 2
(-3425 1225);
DISPLAY 0.872340 (-3425 1225);
PAINT GREEN (-3425 1225);
DISPLAY INVISIBLE (-3425 1225);
FORCEPROP 1 LAST HDL_TAP TRUE
J 2
(-3750 1050);
DISPLAY 0.872340 (-3750 1050);
DISPLAY INVISIBLE (-3750 1050);
FORCEPROP 1 LAST PATH I6
J 2
(-3423 1175);
DISPLAY 0.872340 (-3423 1175);
PAINT GREEN (-3423 1175);
DISPLAY INVISIBLE (-3423 1175);
FORCEADD OFFPAGE..1
(-8950 2125);
FORCEPROP 2 LAST $XR0 353 
J 0
(-9232 2125);
DISPLAY 0.638298 (-9232 2125);
PAINT MONO (-9232 2125);
FORCEPROP 2 LAST CDS_LIB standard
J 0
(-8950 2125);
DISPLAY INVISIBLE (-8950 2125);
FORCEPROP 1 LAST OFFPAGE TRUE
J 0
(-8625 2000);
DISPLAY 0.872340 (-8625 2000);
DISPLAY INVISIBLE (-8625 2000);
FORCEPROP 1 LAST COMMENT_BODY TRUE
J 0
(-8825 2025);
DISPLAY 0.872340 (-8825 2025);
PAINT GREEN (-8825 2025);
DISPLAY INVISIBLE (-8825 2025);
FORCEPROP 2 LAST PATH I60
J 0
(-9200 2175);
DISPLAY 0.680851 (-9200 2175);
DISPLAY INVISIBLE (-9200 2175);
FORCEADD TAP..1
(-7050 4025);
FORCEPROP 3 LASTPIN (-7100 4025) SIG_NAME P5E_CPU1_P3_TX_BUF_DP<10>
J 0
(-7090 4035);
DISPLAY 0.659574 (-7090 4035);
PAINT MONO (-7090 4035);
DISPLAY INVISIBLE (-7090 4035);
FORCEPROP 1 LASTPIN (-7100 4025) BN 10
J 0
(-7112 4033);
DISPLAY 0.680851 (-7112 4033);
PAINT GREEN (-7112 4033);
FORCEPROP 2 LAST CDS_LIB standard
J 0
(-7050 4025);
DISPLAY INVISIBLE (-7050 4025);
FORCEPROP 1 LAST BODY_TYPE PLUMBING
J 0
(-7050 4075);
DISPLAY 0.872340 (-7050 4075);
PAINT GREEN (-7050 4075);
DISPLAY INVISIBLE (-7050 4075);
FORCEPROP 1 LAST HDL_TAP TRUE
J 0
(-6725 3900);
DISPLAY 0.872340 (-6725 3900);
DISPLAY INVISIBLE (-6725 3900);
FORCEPROP 1 LAST PATH I61
J 0
(-7052 4025);
DISPLAY 0.872340 (-7052 4025);
PAINT GREEN (-7052 4025);
DISPLAY INVISIBLE (-7052 4025);
FORCEADD TAP..1
(-7050 4375);
FORCEPROP 3 LASTPIN (-7100 4375) SIG_NAME P5E_CPU1_P3_TX_BUF_DP<11>
J 0
(-7090 4385);
DISPLAY 0.659574 (-7090 4385);
PAINT MONO (-7090 4385);
DISPLAY INVISIBLE (-7090 4385);
FORCEPROP 1 LASTPIN (-7100 4375) BN 11
J 0
(-7112 4383);
DISPLAY 0.680851 (-7112 4383);
PAINT GREEN (-7112 4383);
FORCEPROP 2 LAST CDS_LIB standard
J 0
(-7050 4375);
DISPLAY INVISIBLE (-7050 4375);
FORCEPROP 1 LAST BODY_TYPE PLUMBING
J 0
(-7050 4425);
DISPLAY 0.872340 (-7050 4425);
PAINT GREEN (-7050 4425);
DISPLAY INVISIBLE (-7050 4425);
FORCEPROP 1 LAST HDL_TAP TRUE
J 0
(-6725 4250);
DISPLAY 0.872340 (-6725 4250);
DISPLAY INVISIBLE (-6725 4250);
FORCEPROP 1 LAST PATH I62
J 0
(-7052 4375);
DISPLAY 0.872340 (-7052 4375);
PAINT GREEN (-7052 4375);
DISPLAY INVISIBLE (-7052 4375);
FORCEADD TAP..1
(-6850 4275);
FORCEPROP 3 LASTPIN (-6900 4275) SIG_NAME P5E_CPU1_P3_TX_BUF_DN<11>
J 0
(-6890 4285);
DISPLAY 0.659574 (-6890 4285);
PAINT MONO (-6890 4285);
DISPLAY INVISIBLE (-6890 4285);
FORCEPROP 1 LASTPIN (-6900 4275) BN 11
J 0
(-6912 4283);
DISPLAY 0.680851 (-6912 4283);
PAINT GREEN (-6912 4283);
FORCEPROP 2 LAST CDS_LIB standard
J 0
(-6850 4275);
DISPLAY INVISIBLE (-6850 4275);
FORCEPROP 1 LAST BODY_TYPE PLUMBING
J 0
(-6850 4325);
DISPLAY 0.872340 (-6850 4325);
PAINT GREEN (-6850 4325);
DISPLAY INVISIBLE (-6850 4325);
FORCEPROP 1 LAST HDL_TAP TRUE
J 0
(-6525 4150);
DISPLAY 0.872340 (-6525 4150);
DISPLAY INVISIBLE (-6525 4150);
FORCEPROP 1 LAST PATH I63
J 0
(-6852 4275);
DISPLAY 0.872340 (-6852 4275);
PAINT GREEN (-6852 4275);
DISPLAY INVISIBLE (-6852 4275);
FORCEADD TAP..1
(-7050 4725);
FORCEPROP 3 LASTPIN (-7100 4725) SIG_NAME P5E_CPU1_P3_TX_BUF_DP<12>
J 0
(-7090 4735);
DISPLAY 0.659574 (-7090 4735);
PAINT MONO (-7090 4735);
DISPLAY INVISIBLE (-7090 4735);
FORCEPROP 1 LASTPIN (-7100 4725) BN 12
J 0
(-7112 4733);
DISPLAY 0.680851 (-7112 4733);
PAINT GREEN (-7112 4733);
FORCEPROP 2 LAST CDS_LIB standard
J 0
(-7050 4725);
DISPLAY INVISIBLE (-7050 4725);
FORCEPROP 1 LAST BODY_TYPE PLUMBING
J 0
(-7050 4775);
DISPLAY 0.872340 (-7050 4775);
PAINT GREEN (-7050 4775);
DISPLAY INVISIBLE (-7050 4775);
FORCEPROP 1 LAST HDL_TAP TRUE
J 0
(-6725 4600);
DISPLAY 0.872340 (-6725 4600);
DISPLAY INVISIBLE (-6725 4600);
FORCEPROP 1 LAST PATH I64
J 0
(-7052 4725);
DISPLAY 0.872340 (-7052 4725);
PAINT GREEN (-7052 4725);
DISPLAY INVISIBLE (-7052 4725);
FORCEADD TAP..1
(-6850 4625);
FORCEPROP 3 LASTPIN (-6900 4625) SIG_NAME P5E_CPU1_P3_TX_BUF_DN<12>
J 0
(-6890 4635);
DISPLAY 0.659574 (-6890 4635);
PAINT MONO (-6890 4635);
DISPLAY INVISIBLE (-6890 4635);
FORCEPROP 1 LASTPIN (-6900 4625) BN 12
J 0
(-6912 4633);
DISPLAY 0.680851 (-6912 4633);
PAINT GREEN (-6912 4633);
FORCEPROP 2 LAST CDS_LIB standard
J 0
(-6850 4625);
DISPLAY INVISIBLE (-6850 4625);
FORCEPROP 1 LAST BODY_TYPE PLUMBING
J 0
(-6850 4675);
DISPLAY 0.872340 (-6850 4675);
PAINT GREEN (-6850 4675);
DISPLAY INVISIBLE (-6850 4675);
FORCEPROP 1 LAST HDL_TAP TRUE
J 0
(-6525 4500);
DISPLAY 0.872340 (-6525 4500);
DISPLAY INVISIBLE (-6525 4500);
FORCEPROP 1 LAST PATH I65
J 0
(-6852 4625);
DISPLAY 0.872340 (-6852 4625);
PAINT GREEN (-6852 4625);
DISPLAY INVISIBLE (-6852 4625);
FORCEADD TAP..1
(-6850 4975);
FORCEPROP 3 LASTPIN (-6900 4975) SIG_NAME P5E_CPU1_P3_TX_BUF_DN<13>
J 0
(-6890 4985);
DISPLAY 0.659574 (-6890 4985);
PAINT MONO (-6890 4985);
DISPLAY INVISIBLE (-6890 4985);
FORCEPROP 1 LASTPIN (-6900 4975) BN 13
J 0
(-6912 4983);
DISPLAY 0.680851 (-6912 4983);
PAINT GREEN (-6912 4983);
FORCEPROP 2 LAST CDS_LIB standard
J 0
(-6850 4975);
DISPLAY INVISIBLE (-6850 4975);
FORCEPROP 1 LAST BODY_TYPE PLUMBING
J 0
(-6850 5025);
DISPLAY 0.872340 (-6850 5025);
PAINT GREEN (-6850 5025);
DISPLAY INVISIBLE (-6850 5025);
FORCEPROP 1 LAST HDL_TAP TRUE
J 0
(-6525 4850);
DISPLAY 0.872340 (-6525 4850);
DISPLAY INVISIBLE (-6525 4850);
FORCEPROP 1 LAST PATH I66
J 0
(-6852 4975);
DISPLAY 0.872340 (-6852 4975);
PAINT GREEN (-6852 4975);
DISPLAY INVISIBLE (-6852 4975);
FORCEADD TAP..1
(-7050 5075);
FORCEPROP 3 LASTPIN (-7100 5075) SIG_NAME P5E_CPU1_P3_TX_BUF_DP<13>
J 0
(-7090 5085);
DISPLAY 0.659574 (-7090 5085);
PAINT MONO (-7090 5085);
DISPLAY INVISIBLE (-7090 5085);
FORCEPROP 1 LASTPIN (-7100 5075) BN 13
J 0
(-7112 5083);
DISPLAY 0.680851 (-7112 5083);
PAINT GREEN (-7112 5083);
FORCEPROP 2 LAST CDS_LIB standard
J 0
(-7050 5075);
DISPLAY INVISIBLE (-7050 5075);
FORCEPROP 1 LAST BODY_TYPE PLUMBING
J 0
(-7050 5125);
DISPLAY 0.872340 (-7050 5125);
PAINT GREEN (-7050 5125);
DISPLAY INVISIBLE (-7050 5125);
FORCEPROP 1 LAST HDL_TAP TRUE
J 0
(-6725 4950);
DISPLAY 0.872340 (-6725 4950);
DISPLAY INVISIBLE (-6725 4950);
FORCEPROP 1 LAST PATH I67
J 0
(-7052 5075);
DISPLAY 0.872340 (-7052 5075);
PAINT GREEN (-7052 5075);
DISPLAY INVISIBLE (-7052 5075);
FORCEADD TAP..1
(-7050 5425);
FORCEPROP 3 LASTPIN (-7100 5425) SIG_NAME P5E_CPU1_P3_TX_BUF_DP<14>
J 0
(-7090 5435);
DISPLAY 0.659574 (-7090 5435);
PAINT MONO (-7090 5435);
DISPLAY INVISIBLE (-7090 5435);
FORCEPROP 1 LASTPIN (-7100 5425) BN 14
J 0
(-7112 5433);
DISPLAY 0.680851 (-7112 5433);
PAINT GREEN (-7112 5433);
FORCEPROP 2 LAST CDS_LIB standard
J 0
(-7050 5425);
DISPLAY INVISIBLE (-7050 5425);
FORCEPROP 1 LAST BODY_TYPE PLUMBING
J 0
(-7050 5475);
DISPLAY 0.872340 (-7050 5475);
PAINT GREEN (-7050 5475);
DISPLAY INVISIBLE (-7050 5475);
FORCEPROP 1 LAST HDL_TAP TRUE
J 0
(-6725 5300);
DISPLAY 0.872340 (-6725 5300);
DISPLAY INVISIBLE (-6725 5300);
FORCEPROP 1 LAST PATH I68
J 0
(-7052 5425);
DISPLAY 0.872340 (-7052 5425);
PAINT GREEN (-7052 5425);
DISPLAY INVISIBLE (-7052 5425);
FORCEADD TAP..1
(-6850 5325);
FORCEPROP 3 LASTPIN (-6900 5325) SIG_NAME P5E_CPU1_P3_TX_BUF_DN<14>
J 0
(-6890 5335);
DISPLAY 0.659574 (-6890 5335);
PAINT MONO (-6890 5335);
DISPLAY INVISIBLE (-6890 5335);
FORCEPROP 1 LASTPIN (-6900 5325) BN 14
J 0
(-6912 5333);
DISPLAY 0.680851 (-6912 5333);
PAINT GREEN (-6912 5333);
FORCEPROP 2 LAST CDS_LIB standard
J 0
(-6850 5325);
DISPLAY INVISIBLE (-6850 5325);
FORCEPROP 1 LAST BODY_TYPE PLUMBING
J 0
(-6850 5375);
DISPLAY 0.872340 (-6850 5375);
PAINT GREEN (-6850 5375);
DISPLAY INVISIBLE (-6850 5375);
FORCEPROP 1 LAST HDL_TAP TRUE
J 0
(-6525 5200);
DISPLAY 0.872340 (-6525 5200);
DISPLAY INVISIBLE (-6525 5200);
FORCEPROP 1 LAST PATH I69
J 0
(-6852 5325);
DISPLAY 0.872340 (-6852 5325);
PAINT GREEN (-6852 5325);
DISPLAY INVISIBLE (-6852 5325);
FORCEADD TAP..1
R 2
(-3425 1375);
FORCEPROP 3 LASTPIN (-3375 1375) SIG_NAME P5E_CPU1_P3_TX_BUF_DN<4>
J 0
(-3365 1385);
DISPLAY 0.659574 (-3365 1385);
PAINT MONO (-3365 1385);
DISPLAY INVISIBLE (-3365 1385);
FORCEPROP 1 LASTPIN (-3375 1375) BN 4
J 2
(-3363 1383);
DISPLAY 0.680851 (-3363 1383);
PAINT GREEN (-3363 1383);
FORCEPROP 2 LAST CDS_LIB standard
J 0
(-3425 1375);
DISPLAY INVISIBLE (-3425 1375);
FORCEPROP 1 LAST BODY_TYPE PLUMBING
J 2
(-3425 1425);
DISPLAY 0.872340 (-3425 1425);
PAINT GREEN (-3425 1425);
DISPLAY INVISIBLE (-3425 1425);
FORCEPROP 1 LAST HDL_TAP TRUE
J 2
(-3750 1250);
DISPLAY 0.872340 (-3750 1250);
DISPLAY INVISIBLE (-3750 1250);
FORCEPROP 1 LAST PATH I7
J 2
(-3423 1375);
DISPLAY 0.872340 (-3423 1375);
PAINT GREEN (-3423 1375);
DISPLAY INVISIBLE (-3423 1375);
FORCEADD TAP..1
(-7050 5775);
FORCEPROP 3 LASTPIN (-7100 5775) SIG_NAME P5E_CPU1_P3_TX_BUF_DP<15>
J 0
(-7090 5785);
DISPLAY 0.659574 (-7090 5785);
PAINT MONO (-7090 5785);
DISPLAY INVISIBLE (-7090 5785);
FORCEPROP 1 LASTPIN (-7100 5775) BN 15
J 0
(-7112 5783);
DISPLAY 0.680851 (-7112 5783);
PAINT GREEN (-7112 5783);
FORCEPROP 2 LAST CDS_LIB standard
J 0
(-7050 5775);
DISPLAY INVISIBLE (-7050 5775);
FORCEPROP 1 LAST BODY_TYPE PLUMBING
J 0
(-7050 5825);
DISPLAY 0.872340 (-7050 5825);
PAINT GREEN (-7050 5825);
DISPLAY INVISIBLE (-7050 5825);
FORCEPROP 1 LAST HDL_TAP TRUE
J 0
(-6725 5650);
DISPLAY 0.872340 (-6725 5650);
DISPLAY INVISIBLE (-6725 5650);
FORCEPROP 1 LAST PATH I70
J 0
(-7052 5775);
DISPLAY 0.872340 (-7052 5775);
PAINT GREEN (-7052 5775);
DISPLAY INVISIBLE (-7052 5775);
FORCEADD TAP..1
(-6850 5675);
FORCEPROP 3 LASTPIN (-6900 5675) SIG_NAME P5E_CPU1_P3_TX_BUF_DN<15>
J 0
(-6890 5685);
DISPLAY 0.659574 (-6890 5685);
PAINT MONO (-6890 5685);
DISPLAY INVISIBLE (-6890 5685);
FORCEPROP 1 LASTPIN (-6900 5675) BN 15
J 0
(-6912 5683);
DISPLAY 0.680851 (-6912 5683);
PAINT GREEN (-6912 5683);
FORCEPROP 2 LAST CDS_LIB standard
J 0
(-6850 5675);
DISPLAY INVISIBLE (-6850 5675);
FORCEPROP 1 LAST BODY_TYPE PLUMBING
J 0
(-6850 5725);
DISPLAY 0.872340 (-6850 5725);
PAINT GREEN (-6850 5725);
DISPLAY INVISIBLE (-6850 5725);
FORCEPROP 1 LAST HDL_TAP TRUE
J 0
(-6525 5550);
DISPLAY 0.872340 (-6525 5550);
DISPLAY INVISIBLE (-6525 5550);
FORCEPROP 1 LAST PATH I71
J 0
(-6852 5675);
DISPLAY 0.872340 (-6852 5675);
PAINT GREEN (-6852 5675);
DISPLAY INVISIBLE (-6852 5675);
FORCEADD OFFPAGE..5
R 2
(-5875 5700);
FORCEPROP 2 LAST $XR0 353 
J 0
(-5686 5700);
DISPLAY 0.638298 (-5686 5700);
PAINT MONO (-5686 5700);
FORCEPROP 2 LAST CDS_LIB standard
J 0
(-5875 5700);
DISPLAY INVISIBLE (-5875 5700);
FORCEPROP 1 LAST OFFPAGE TRUE
J 2
(-6200 5575);
DISPLAY 0.872340 (-6200 5575);
PAINT GREEN (-6200 5575);
DISPLAY INVISIBLE (-6200 5575);
FORCEPROP 1 LAST COMMENT_BODY TRUE
J 2
(-5975 5625);
DISPLAY 0.872340 (-5975 5625);
PAINT GREEN (-5975 5625);
DISPLAY INVISIBLE (-5975 5625);
FORCEPROP 2 LAST PATH I72
J 0
(-5700 5775);
DISPLAY 0.680851 (-5700 5775);
DISPLAY INVISIBLE (-5700 5775);
FORCEADD OFFPAGE..5
R 2
(-5850 5800);
FORCEPROP 2 LAST $XR0 353 
J 0
(-5661 5800);
DISPLAY 0.638298 (-5661 5800);
PAINT MONO (-5661 5800);
FORCEPROP 2 LAST CDS_LIB standard
J 0
(-5850 5800);
DISPLAY INVISIBLE (-5850 5800);
FORCEPROP 1 LAST OFFPAGE TRUE
J 2
(-6175 5675);
DISPLAY 0.872340 (-6175 5675);
PAINT GREEN (-6175 5675);
DISPLAY INVISIBLE (-6175 5675);
FORCEPROP 1 LAST COMMENT_BODY TRUE
J 2
(-5950 5725);
DISPLAY 0.872340 (-5950 5725);
PAINT GREEN (-5950 5725);
DISPLAY INVISIBLE (-5950 5725);
FORCEPROP 2 LAST PATH I73
J 0
(-5675 5875);
DISPLAY 0.680851 (-5675 5875);
DISPLAY INVISIBLE (-5675 5875);
FORCEADD TAP..1
R 2
(-8000 650);
FORCEPROP 3 LASTPIN (-7950 650) SIG_NAME P5E_CPU1_P3_TX_BUF_DN<15>
J 0
(-7940 660);
DISPLAY 0.659574 (-7940 660);
PAINT MONO (-7940 660);
DISPLAY INVISIBLE (-7940 660);
FORCEPROP 1 LASTPIN (-7950 650) BN 15
J 2
(-7938 658);
DISPLAY 0.680851 (-7938 658);
PAINT GREEN (-7938 658);
FORCEPROP 2 LAST CDS_LIB standard
J 0
(-8000 650);
DISPLAY INVISIBLE (-8000 650);
FORCEPROP 1 LAST BODY_TYPE PLUMBING
J 2
(-8000 700);
DISPLAY 0.872340 (-8000 700);
PAINT GREEN (-8000 700);
DISPLAY INVISIBLE (-8000 700);
FORCEPROP 1 LAST HDL_TAP TRUE
J 2
(-8325 525);
DISPLAY 0.872340 (-8325 525);
DISPLAY INVISIBLE (-8325 525);
FORCEPROP 1 LAST PATH I74
J 2
(-7998 650);
DISPLAY 0.872340 (-7998 650);
PAINT GREEN (-7998 650);
DISPLAY INVISIBLE (-7998 650);
FORCEADD TAP..1
R 2
(-8000 850);
FORCEPROP 3 LASTPIN (-7950 850) SIG_NAME P5E_CPU1_P3_TX_BUF_DN<14>
J 0
(-7940 860);
DISPLAY 0.659574 (-7940 860);
PAINT MONO (-7940 860);
DISPLAY INVISIBLE (-7940 860);
FORCEPROP 1 LASTPIN (-7950 850) BN 14
J 2
(-7938 858);
DISPLAY 0.680851 (-7938 858);
PAINT GREEN (-7938 858);
FORCEPROP 2 LAST CDS_LIB standard
J 0
(-8000 850);
DISPLAY INVISIBLE (-8000 850);
FORCEPROP 1 LAST BODY_TYPE PLUMBING
J 2
(-8000 900);
DISPLAY 0.872340 (-8000 900);
PAINT GREEN (-8000 900);
DISPLAY INVISIBLE (-8000 900);
FORCEPROP 1 LAST HDL_TAP TRUE
J 2
(-8325 725);
DISPLAY 0.872340 (-8325 725);
DISPLAY INVISIBLE (-8325 725);
FORCEPROP 1 LAST PATH I75
J 2
(-7998 850);
DISPLAY 0.872340 (-7998 850);
PAINT GREEN (-7998 850);
DISPLAY INVISIBLE (-7998 850);
FORCEADD TAP..1
R 2
(-7750 700);
FORCEPROP 3 LASTPIN (-7700 700) SIG_NAME P5E_CPU1_P3_TX_BUF_DP<15>
J 0
(-7690 710);
DISPLAY 0.659574 (-7690 710);
PAINT MONO (-7690 710);
DISPLAY INVISIBLE (-7690 710);
FORCEPROP 1 LASTPIN (-7700 700) BN 15
J 2
(-7688 708);
DISPLAY 0.680851 (-7688 708);
PAINT GREEN (-7688 708);
FORCEPROP 2 LAST CDS_LIB standard
J 0
(-7750 700);
DISPLAY INVISIBLE (-7750 700);
FORCEPROP 1 LAST BODY_TYPE PLUMBING
J 2
(-7750 750);
DISPLAY 0.872340 (-7750 750);
PAINT GREEN (-7750 750);
DISPLAY INVISIBLE (-7750 750);
FORCEPROP 1 LAST HDL_TAP TRUE
J 2
(-8075 575);
DISPLAY 0.872340 (-8075 575);
DISPLAY INVISIBLE (-8075 575);
FORCEPROP 1 LAST PATH I76
J 2
(-7748 700);
DISPLAY 0.872340 (-7748 700);
PAINT GREEN (-7748 700);
DISPLAY INVISIBLE (-7748 700);
FORCEADD TAP..1
R 2
(-7750 900);
FORCEPROP 3 LASTPIN (-7700 900) SIG_NAME P5E_CPU1_P3_TX_BUF_DP<14>
J 0
(-7690 910);
DISPLAY 0.659574 (-7690 910);
PAINT MONO (-7690 910);
DISPLAY INVISIBLE (-7690 910);
FORCEPROP 1 LASTPIN (-7700 900) BN 14
J 2
(-7688 908);
DISPLAY 0.680851 (-7688 908);
PAINT GREEN (-7688 908);
FORCEPROP 2 LAST CDS_LIB standard
J 0
(-7750 900);
DISPLAY INVISIBLE (-7750 900);
FORCEPROP 1 LAST BODY_TYPE PLUMBING
J 2
(-7750 950);
DISPLAY 0.872340 (-7750 950);
PAINT GREEN (-7750 950);
DISPLAY INVISIBLE (-7750 950);
FORCEPROP 1 LAST HDL_TAP TRUE
J 2
(-8075 775);
DISPLAY 0.872340 (-8075 775);
DISPLAY INVISIBLE (-8075 775);
FORCEPROP 1 LAST PATH I77
J 2
(-7748 900);
DISPLAY 0.872340 (-7748 900);
PAINT GREEN (-7748 900);
DISPLAY INVISIBLE (-7748 900);
FORCEADD TAP..1
R 2
(-8000 1250);
FORCEPROP 3 LASTPIN (-7950 1250) SIG_NAME P5E_CPU1_P3_TX_BUF_DN<12>
J 0
(-7940 1260);
DISPLAY 0.659574 (-7940 1260);
PAINT MONO (-7940 1260);
DISPLAY INVISIBLE (-7940 1260);
FORCEPROP 1 LASTPIN (-7950 1250) BN 12
J 2
(-7938 1258);
DISPLAY 0.680851 (-7938 1258);
PAINT GREEN (-7938 1258);
FORCEPROP 2 LAST CDS_LIB standard
J 0
(-8000 1250);
DISPLAY INVISIBLE (-8000 1250);
FORCEPROP 1 LAST BODY_TYPE PLUMBING
J 2
(-8000 1300);
DISPLAY 0.872340 (-8000 1300);
PAINT GREEN (-8000 1300);
DISPLAY INVISIBLE (-8000 1300);
FORCEPROP 1 LAST HDL_TAP TRUE
J 2
(-8325 1125);
DISPLAY 0.872340 (-8325 1125);
DISPLAY INVISIBLE (-8325 1125);
FORCEPROP 1 LAST PATH I78
J 2
(-7998 1250);
DISPLAY 0.872340 (-7998 1250);
PAINT GREEN (-7998 1250);
DISPLAY INVISIBLE (-7998 1250);
FORCEADD TAP..1
R 2
(-8000 1050);
FORCEPROP 3 LASTPIN (-7950 1050) SIG_NAME P5E_CPU1_P3_TX_BUF_DN<13>
J 0
(-7940 1060);
DISPLAY 0.659574 (-7940 1060);
PAINT MONO (-7940 1060);
DISPLAY INVISIBLE (-7940 1060);
FORCEPROP 1 LASTPIN (-7950 1050) BN 13
J 2
(-7938 1058);
DISPLAY 0.680851 (-7938 1058);
PAINT GREEN (-7938 1058);
FORCEPROP 2 LAST CDS_LIB standard
J 0
(-8000 1050);
DISPLAY INVISIBLE (-8000 1050);
FORCEPROP 1 LAST BODY_TYPE PLUMBING
J 2
(-8000 1100);
DISPLAY 0.872340 (-8000 1100);
PAINT GREEN (-8000 1100);
DISPLAY INVISIBLE (-8000 1100);
FORCEPROP 1 LAST HDL_TAP TRUE
J 2
(-8325 925);
DISPLAY 0.872340 (-8325 925);
DISPLAY INVISIBLE (-8325 925);
FORCEPROP 1 LAST PATH I79
J 2
(-7998 1050);
DISPLAY 0.872340 (-7998 1050);
PAINT GREEN (-7998 1050);
DISPLAY INVISIBLE (-7998 1050);
FORCEADD TAP..1
R 2
(-3425 1575);
FORCEPROP 3 LASTPIN (-3375 1575) SIG_NAME P5E_CPU1_P3_TX_BUF_DN<3>
J 0
(-3365 1585);
DISPLAY 0.659574 (-3365 1585);
PAINT MONO (-3365 1585);
DISPLAY INVISIBLE (-3365 1585);
FORCEPROP 1 LASTPIN (-3375 1575) BN 3
J 2
(-3363 1583);
DISPLAY 0.680851 (-3363 1583);
PAINT GREEN (-3363 1583);
FORCEPROP 2 LAST CDS_LIB standard
J 0
(-3425 1575);
DISPLAY INVISIBLE (-3425 1575);
FORCEPROP 1 LAST BODY_TYPE PLUMBING
J 2
(-3425 1625);
DISPLAY 0.872340 (-3425 1625);
PAINT GREEN (-3425 1625);
DISPLAY INVISIBLE (-3425 1625);
FORCEPROP 1 LAST HDL_TAP TRUE
J 2
(-3750 1450);
DISPLAY 0.872340 (-3750 1450);
DISPLAY INVISIBLE (-3750 1450);
FORCEPROP 1 LAST PATH I8
J 2
(-3423 1575);
DISPLAY 0.872340 (-3423 1575);
PAINT GREEN (-3423 1575);
DISPLAY INVISIBLE (-3423 1575);
FORCEADD TAP..1
R 2
(-7750 1100);
FORCEPROP 3 LASTPIN (-7700 1100) SIG_NAME P5E_CPU1_P3_TX_BUF_DP<13>
J 0
(-7690 1110);
DISPLAY 0.659574 (-7690 1110);
PAINT MONO (-7690 1110);
DISPLAY INVISIBLE (-7690 1110);
FORCEPROP 1 LASTPIN (-7700 1100) BN 13
J 2
(-7688 1108);
DISPLAY 0.680851 (-7688 1108);
PAINT GREEN (-7688 1108);
FORCEPROP 2 LAST CDS_LIB standard
J 0
(-7750 1100);
DISPLAY INVISIBLE (-7750 1100);
FORCEPROP 1 LAST BODY_TYPE PLUMBING
J 2
(-7750 1150);
DISPLAY 0.872340 (-7750 1150);
PAINT GREEN (-7750 1150);
DISPLAY INVISIBLE (-7750 1150);
FORCEPROP 1 LAST HDL_TAP TRUE
J 2
(-8075 975);
DISPLAY 0.872340 (-8075 975);
DISPLAY INVISIBLE (-8075 975);
FORCEPROP 1 LAST PATH I80
J 2
(-7748 1100);
DISPLAY 0.872340 (-7748 1100);
PAINT GREEN (-7748 1100);
DISPLAY INVISIBLE (-7748 1100);
FORCEADD TAP..1
R 2
(-7750 1300);
FORCEPROP 3 LASTPIN (-7700 1300) SIG_NAME P5E_CPU1_P3_TX_BUF_DP<12>
J 0
(-7690 1310);
DISPLAY 0.659574 (-7690 1310);
PAINT MONO (-7690 1310);
DISPLAY INVISIBLE (-7690 1310);
FORCEPROP 1 LASTPIN (-7700 1300) BN 12
J 2
(-7688 1308);
DISPLAY 0.680851 (-7688 1308);
PAINT GREEN (-7688 1308);
FORCEPROP 2 LAST CDS_LIB standard
J 0
(-7750 1300);
DISPLAY INVISIBLE (-7750 1300);
FORCEPROP 1 LAST BODY_TYPE PLUMBING
J 2
(-7750 1350);
DISPLAY 0.872340 (-7750 1350);
PAINT GREEN (-7750 1350);
DISPLAY INVISIBLE (-7750 1350);
FORCEPROP 1 LAST HDL_TAP TRUE
J 2
(-8075 1175);
DISPLAY 0.872340 (-8075 1175);
DISPLAY INVISIBLE (-8075 1175);
FORCEPROP 1 LAST PATH I81
J 2
(-7748 1300);
DISPLAY 0.872340 (-7748 1300);
PAINT GREEN (-7748 1300);
DISPLAY INVISIBLE (-7748 1300);
FORCEADD TAP..1
R 2
(-8000 1650);
FORCEPROP 3 LASTPIN (-7950 1650) SIG_NAME P5E_CPU1_P3_TX_BUF_DN<10>
J 0
(-7940 1660);
DISPLAY 0.659574 (-7940 1660);
PAINT MONO (-7940 1660);
DISPLAY INVISIBLE (-7940 1660);
FORCEPROP 1 LASTPIN (-7950 1650) BN 10
J 2
(-7938 1658);
DISPLAY 0.680851 (-7938 1658);
PAINT GREEN (-7938 1658);
FORCEPROP 2 LAST CDS_LIB standard
J 0
(-8000 1650);
DISPLAY INVISIBLE (-8000 1650);
FORCEPROP 1 LAST BODY_TYPE PLUMBING
J 2
(-8000 1700);
DISPLAY 0.872340 (-8000 1700);
PAINT GREEN (-8000 1700);
DISPLAY INVISIBLE (-8000 1700);
FORCEPROP 1 LAST HDL_TAP TRUE
J 2
(-8325 1525);
DISPLAY 0.872340 (-8325 1525);
DISPLAY INVISIBLE (-8325 1525);
FORCEPROP 1 LAST PATH I82
J 2
(-7998 1650);
DISPLAY 0.872340 (-7998 1650);
PAINT GREEN (-7998 1650);
DISPLAY INVISIBLE (-7998 1650);
FORCEADD TAP..1
R 2
(-8000 1450);
FORCEPROP 3 LASTPIN (-7950 1450) SIG_NAME P5E_CPU1_P3_TX_BUF_DN<11>
J 0
(-7940 1460);
DISPLAY 0.659574 (-7940 1460);
PAINT MONO (-7940 1460);
DISPLAY INVISIBLE (-7940 1460);
FORCEPROP 1 LASTPIN (-7950 1450) BN 11
J 2
(-7938 1458);
DISPLAY 0.680851 (-7938 1458);
PAINT GREEN (-7938 1458);
FORCEPROP 2 LAST CDS_LIB standard
J 0
(-8000 1450);
DISPLAY INVISIBLE (-8000 1450);
FORCEPROP 1 LAST BODY_TYPE PLUMBING
J 2
(-8000 1500);
DISPLAY 0.872340 (-8000 1500);
PAINT GREEN (-8000 1500);
DISPLAY INVISIBLE (-8000 1500);
FORCEPROP 1 LAST HDL_TAP TRUE
J 2
(-8325 1325);
DISPLAY 0.872340 (-8325 1325);
DISPLAY INVISIBLE (-8325 1325);
FORCEPROP 1 LAST PATH I83
J 2
(-7998 1450);
DISPLAY 0.872340 (-7998 1450);
PAINT GREEN (-7998 1450);
DISPLAY INVISIBLE (-7998 1450);
FORCEADD TAP..1
R 2
(-8000 1850);
FORCEPROP 3 LASTPIN (-7950 1850) SIG_NAME P5E_CPU1_P3_TX_BUF_DN<9>
J 0
(-7940 1860);
DISPLAY 0.659574 (-7940 1860);
PAINT MONO (-7940 1860);
DISPLAY INVISIBLE (-7940 1860);
FORCEPROP 1 LASTPIN (-7950 1850) BN 9
J 2
(-7938 1858);
DISPLAY 0.680851 (-7938 1858);
PAINT GREEN (-7938 1858);
FORCEPROP 2 LAST CDS_LIB standard
J 0
(-8000 1850);
DISPLAY INVISIBLE (-8000 1850);
FORCEPROP 1 LAST BODY_TYPE PLUMBING
J 2
(-8000 1900);
DISPLAY 0.872340 (-8000 1900);
PAINT GREEN (-8000 1900);
DISPLAY INVISIBLE (-8000 1900);
FORCEPROP 1 LAST HDL_TAP TRUE
J 2
(-8325 1725);
DISPLAY 0.872340 (-8325 1725);
DISPLAY INVISIBLE (-8325 1725);
FORCEPROP 1 LAST PATH I84
J 2
(-7998 1850);
DISPLAY 0.872340 (-7998 1850);
PAINT GREEN (-7998 1850);
DISPLAY INVISIBLE (-7998 1850);
FORCEADD TAP..1
R 2
(-7750 1500);
FORCEPROP 3 LASTPIN (-7700 1500) SIG_NAME P5E_CPU1_P3_TX_BUF_DP<11>
J 0
(-7690 1510);
DISPLAY 0.659574 (-7690 1510);
PAINT MONO (-7690 1510);
DISPLAY INVISIBLE (-7690 1510);
FORCEPROP 1 LASTPIN (-7700 1500) BN 11
J 2
(-7688 1508);
DISPLAY 0.680851 (-7688 1508);
PAINT GREEN (-7688 1508);
FORCEPROP 2 LAST CDS_LIB standard
J 0
(-7750 1500);
DISPLAY INVISIBLE (-7750 1500);
FORCEPROP 1 LAST BODY_TYPE PLUMBING
J 2
(-7750 1550);
DISPLAY 0.872340 (-7750 1550);
PAINT GREEN (-7750 1550);
DISPLAY INVISIBLE (-7750 1550);
FORCEPROP 1 LAST HDL_TAP TRUE
J 2
(-8075 1375);
DISPLAY 0.872340 (-8075 1375);
DISPLAY INVISIBLE (-8075 1375);
FORCEPROP 1 LAST PATH I85
J 2
(-7748 1500);
DISPLAY 0.872340 (-7748 1500);
PAINT GREEN (-7748 1500);
DISPLAY INVISIBLE (-7748 1500);
FORCEADD TAP..1
R 2
(-7750 1700);
FORCEPROP 3 LASTPIN (-7700 1700) SIG_NAME P5E_CPU1_P3_TX_BUF_DP<10>
J 0
(-7690 1710);
DISPLAY 0.659574 (-7690 1710);
PAINT MONO (-7690 1710);
DISPLAY INVISIBLE (-7690 1710);
FORCEPROP 1 LASTPIN (-7700 1700) BN 10
J 2
(-7688 1708);
DISPLAY 0.680851 (-7688 1708);
PAINT GREEN (-7688 1708);
FORCEPROP 2 LAST CDS_LIB standard
J 0
(-7750 1700);
DISPLAY INVISIBLE (-7750 1700);
FORCEPROP 1 LAST BODY_TYPE PLUMBING
J 2
(-7750 1750);
DISPLAY 0.872340 (-7750 1750);
PAINT GREEN (-7750 1750);
DISPLAY INVISIBLE (-7750 1750);
FORCEPROP 1 LAST HDL_TAP TRUE
J 2
(-8075 1575);
DISPLAY 0.872340 (-8075 1575);
DISPLAY INVISIBLE (-8075 1575);
FORCEPROP 1 LAST PATH I86
J 2
(-7748 1700);
DISPLAY 0.872340 (-7748 1700);
PAINT GREEN (-7748 1700);
DISPLAY INVISIBLE (-7748 1700);
FORCEADD TAP..1
R 2
(-7750 1900);
FORCEPROP 3 LASTPIN (-7700 1900) SIG_NAME P5E_CPU1_P3_TX_BUF_DP<9>
J 0
(-7690 1910);
DISPLAY 0.659574 (-7690 1910);
PAINT MONO (-7690 1910);
DISPLAY INVISIBLE (-7690 1910);
FORCEPROP 1 LASTPIN (-7700 1900) BN 9
J 2
(-7688 1908);
DISPLAY 0.680851 (-7688 1908);
PAINT GREEN (-7688 1908);
FORCEPROP 2 LAST CDS_LIB standard
J 0
(-7750 1900);
DISPLAY INVISIBLE (-7750 1900);
FORCEPROP 1 LAST BODY_TYPE PLUMBING
J 2
(-7750 1950);
DISPLAY 0.872340 (-7750 1950);
PAINT GREEN (-7750 1950);
DISPLAY INVISIBLE (-7750 1950);
FORCEPROP 1 LAST HDL_TAP TRUE
J 2
(-8075 1775);
DISPLAY 0.872340 (-8075 1775);
DISPLAY INVISIBLE (-8075 1775);
FORCEPROP 1 LAST PATH I87
J 2
(-7748 1900);
DISPLAY 0.872340 (-7748 1900);
PAINT GREEN (-7748 1900);
DISPLAY INVISIBLE (-7748 1900);
FORCEADD Q_CAP_DIFFBUS..2
R 2
(-7025 650);
FORCEPROP 1 LAST LOCATION C6756
J 2
(-6750 650);
DISPLAY 0.723404 (-6750 650);
PAINT GREEN (-6750 650);
FORCEPROP 2 LAST $SEC 1
J 2
(-6850 725);
DISPLAY 0.680851 (-6850 725);
PAINT MONO (-6850 725);
DISPLAY INVISIBLE (-6850 725);
FORCEPROP 2 LAST CDS_SEC 1
J 2
(-6850 725);
DISPLAY 0.680851 (-6850 725);
DISPLAY INVISIBLE (-6850 725);
FORCEPROP 2 LASTPIN (-6950 650) $PN 1
J 0
(-6940 660);
DISPLAY 0.808511 (-6940 660);
FORCEPROP 2 LASTPIN (-7100 650) $PN 2
J 2
(-7110 660);
DISPLAY 0.808511 (-7110 660);
FORCEPROP 2 LAST VALUE DIFF BUS_0.22UF
J 2
(-7175 650);
DISPLAY 0.553191 (-7175 650);
FORCEPROP 2 LAST TOLERANCE 20%
J 2
(-7100 700);
DISPLAY 0.553191 (-7100 700);
DISPLAY INVISIBLE (-7100 700);
FORCEPROP 2 LAST PACK_TYPE C0201
J 2
(-7200 700);
DISPLAY 0.553191 (-7200 700);
DISPLAY INVISIBLE (-7200 700);
FORCEPROP 1 LAST MATERIAL X6S
J 2
(-7016 729);
DISPLAY 0.574468 (-7016 729);
PAINT GREEN (-7016 729);
DISPLAY INVISIBLE (-7016 729);
FORCEPROP 2 LAST VOLTAGE 6.3V
J 2
(-7375 700);
DISPLAY 0.553191 (-7375 700);
DISPLAY INVISIBLE (-7375 700);
FORCEPROP 1 LAST PIN_NAMES_ROTATE TRUE
J 2
(-7025 650);
DISPLAY 0.489362 (-7025 650);
PAINT GREEN (-7025 650);
DISPLAY INVISIBLE (-7025 650);
FORCEPROP 2 LAST CDS_LIB pure_quanta
J 2
(-7025 650);
DISPLAY INVISIBLE (-7025 650);
FORCEPROP 1 LAST CDS_LMAN_SYM_OUTLINE -25,50,25,-50
J 2
(-7025 650);
DISPLAY 0.468085 (-7025 650);
PAINT GREEN (-7025 650);
DISPLAY INVISIBLE (-7025 650);
FORCEPROP 1 LAST PATH I88
J 2
(-7025 650);
DISPLAY 0.723404 (-7025 650);
DISPLAY INVISIBLE (-7025 650);
FORCEPROP 1 LAST PART_NUMBER SP_CH4221MEE01
J 2
(-7141 738);
DISPLAY 0.574468 (-7141 738);
PAINT GREEN (-7141 738);
DISPLAY INVISIBLE (-7141 738);
FORCEPROP 1 LAST LOCATION C6756
J 0
(-6775 725);
DISPLAY 1.021277 (-6775 725);
DISPLAY INVISIBLE (-6775 725);
FORCEADD Q_CAP_DIFFBUS..2
R 2
(-7025 700);
FORCEPROP 1 LAST LOCATION C6755
J 2
(-6750 700);
DISPLAY 0.723404 (-6750 700);
PAINT GREEN (-6750 700);
FORCEPROP 2 LAST $SEC 1
J 2
(-6850 775);
DISPLAY 0.680851 (-6850 775);
PAINT MONO (-6850 775);
DISPLAY INVISIBLE (-6850 775);
FORCEPROP 2 LAST CDS_SEC 1
J 2
(-6850 775);
DISPLAY 0.680851 (-6850 775);
DISPLAY INVISIBLE (-6850 775);
FORCEPROP 2 LASTPIN (-6950 700) $PN 1
J 0
(-6940 710);
DISPLAY 0.808511 (-6940 710);
FORCEPROP 2 LASTPIN (-7100 700) $PN 2
J 2
(-7110 710);
DISPLAY 0.808511 (-7110 710);
FORCEPROP 2 LAST VALUE DIFF BUS_0.22UF
J 2
(-7175 700);
DISPLAY 0.553191 (-7175 700);
FORCEPROP 2 LAST TOLERANCE 20%
J 2
(-7100 750);
DISPLAY 0.553191 (-7100 750);
DISPLAY INVISIBLE (-7100 750);
FORCEPROP 2 LAST PACK_TYPE C0201
J 2
(-7200 750);
DISPLAY 0.553191 (-7200 750);
DISPLAY INVISIBLE (-7200 750);
FORCEPROP 1 LAST MATERIAL X6S
J 2
(-7016 779);
DISPLAY 0.574468 (-7016 779);
PAINT GREEN (-7016 779);
DISPLAY INVISIBLE (-7016 779);
FORCEPROP 2 LAST VOLTAGE 6.3V
J 2
(-7375 750);
DISPLAY 0.553191 (-7375 750);
DISPLAY INVISIBLE (-7375 750);
FORCEPROP 1 LAST PIN_NAMES_ROTATE TRUE
J 2
(-7025 700);
DISPLAY 0.489362 (-7025 700);
PAINT GREEN (-7025 700);
DISPLAY INVISIBLE (-7025 700);
FORCEPROP 2 LAST CDS_LIB pure_quanta
J 2
(-7025 700);
DISPLAY INVISIBLE (-7025 700);
FORCEPROP 1 LAST CDS_LMAN_SYM_OUTLINE -25,50,25,-50
J 2
(-7025 700);
DISPLAY 0.468085 (-7025 700);
PAINT GREEN (-7025 700);
DISPLAY INVISIBLE (-7025 700);
FORCEPROP 1 LAST PATH I89
J 2
(-7025 700);
DISPLAY 0.723404 (-7025 700);
DISPLAY INVISIBLE (-7025 700);
FORCEPROP 1 LAST PART_NUMBER SP_CH4221MEE01
J 2
(-7141 788);
DISPLAY 0.574468 (-7141 788);
PAINT GREEN (-7141 788);
DISPLAY INVISIBLE (-7141 788);
FORCEPROP 1 LAST LOCATION C6755
J 0
(-6775 775);
DISPLAY 1.021277 (-6775 775);
DISPLAY INVISIBLE (-6775 775);
FORCEADD TAP..1
R 2
(-3425 1775);
FORCEPROP 3 LASTPIN (-3375 1775) SIG_NAME P5E_CPU1_P3_TX_BUF_DN<2>
J 0
(-3365 1785);
DISPLAY 0.659574 (-3365 1785);
PAINT MONO (-3365 1785);
DISPLAY INVISIBLE (-3365 1785);
FORCEPROP 1 LASTPIN (-3375 1775) BN 2
J 2
(-3363 1783);
DISPLAY 0.680851 (-3363 1783);
PAINT GREEN (-3363 1783);
FORCEPROP 2 LAST CDS_LIB standard
J 0
(-3425 1775);
DISPLAY INVISIBLE (-3425 1775);
FORCEPROP 1 LAST BODY_TYPE PLUMBING
J 2
(-3425 1825);
DISPLAY 0.872340 (-3425 1825);
PAINT GREEN (-3425 1825);
DISPLAY INVISIBLE (-3425 1825);
FORCEPROP 1 LAST HDL_TAP TRUE
J 2
(-3750 1650);
DISPLAY 0.872340 (-3750 1650);
DISPLAY INVISIBLE (-3750 1650);
FORCEPROP 1 LAST PATH I9
J 2
(-3423 1775);
DISPLAY 0.872340 (-3423 1775);
PAINT GREEN (-3423 1775);
DISPLAY INVISIBLE (-3423 1775);
FORCEADD Q_CAP_DIFFBUS..2
R 2
(-7025 850);
FORCEPROP 1 LAST LOCATION C6754
J 2
(-6750 850);
DISPLAY 0.723404 (-6750 850);
PAINT GREEN (-6750 850);
FORCEPROP 2 LAST $SEC 1
J 2
(-6850 925);
DISPLAY 0.680851 (-6850 925);
PAINT MONO (-6850 925);
DISPLAY INVISIBLE (-6850 925);
FORCEPROP 2 LAST CDS_SEC 1
J 2
(-6850 925);
DISPLAY 0.680851 (-6850 925);
DISPLAY INVISIBLE (-6850 925);
FORCEPROP 2 LASTPIN (-6950 850) $PN 1
J 0
(-6940 860);
DISPLAY 0.808511 (-6940 860);
FORCEPROP 2 LASTPIN (-7100 850) $PN 2
J 2
(-7110 860);
DISPLAY 0.808511 (-7110 860);
FORCEPROP 2 LAST VALUE DIFF BUS_0.22UF
J 2
(-7175 850);
DISPLAY 0.553191 (-7175 850);
FORCEPROP 2 LAST TOLERANCE 20%
J 2
(-7100 900);
DISPLAY 0.553191 (-7100 900);
DISPLAY INVISIBLE (-7100 900);
FORCEPROP 2 LAST PACK_TYPE C0201
J 2
(-7200 900);
DISPLAY 0.553191 (-7200 900);
DISPLAY INVISIBLE (-7200 900);
FORCEPROP 1 LAST MATERIAL X6S
J 2
(-7016 929);
DISPLAY 0.574468 (-7016 929);
PAINT GREEN (-7016 929);
DISPLAY INVISIBLE (-7016 929);
FORCEPROP 2 LAST VOLTAGE 6.3V
J 2
(-7375 900);
DISPLAY 0.553191 (-7375 900);
DISPLAY INVISIBLE (-7375 900);
FORCEPROP 1 LAST PIN_NAMES_ROTATE TRUE
J 2
(-7025 850);
DISPLAY 0.489362 (-7025 850);
PAINT GREEN (-7025 850);
DISPLAY INVISIBLE (-7025 850);
FORCEPROP 2 LAST CDS_LIB pure_quanta
J 2
(-7025 850);
DISPLAY INVISIBLE (-7025 850);
FORCEPROP 1 LAST CDS_LMAN_SYM_OUTLINE -25,50,25,-50
J 2
(-7025 850);
DISPLAY 0.468085 (-7025 850);
PAINT GREEN (-7025 850);
DISPLAY INVISIBLE (-7025 850);
FORCEPROP 1 LAST PATH I90
J 2
(-7025 850);
DISPLAY 0.723404 (-7025 850);
DISPLAY INVISIBLE (-7025 850);
FORCEPROP 1 LAST PART_NUMBER SP_CH4221MEE01
J 2
(-7141 938);
DISPLAY 0.574468 (-7141 938);
PAINT GREEN (-7141 938);
DISPLAY INVISIBLE (-7141 938);
FORCEPROP 1 LAST LOCATION C6754
J 0
(-6775 925);
DISPLAY 1.021277 (-6775 925);
DISPLAY INVISIBLE (-6775 925);
FORCEADD Q_CAP_DIFFBUS..2
R 2
(-7025 900);
FORCEPROP 1 LAST LOCATION C6753
J 2
(-6750 900);
DISPLAY 0.723404 (-6750 900);
PAINT GREEN (-6750 900);
FORCEPROP 2 LAST $SEC 1
J 2
(-6850 975);
DISPLAY 0.680851 (-6850 975);
PAINT MONO (-6850 975);
DISPLAY INVISIBLE (-6850 975);
FORCEPROP 2 LAST CDS_SEC 1
J 2
(-6850 975);
DISPLAY 0.680851 (-6850 975);
DISPLAY INVISIBLE (-6850 975);
FORCEPROP 2 LASTPIN (-6950 900) $PN 1
J 0
(-6940 910);
DISPLAY 0.808511 (-6940 910);
FORCEPROP 2 LASTPIN (-7100 900) $PN 2
J 2
(-7110 910);
DISPLAY 0.808511 (-7110 910);
FORCEPROP 2 LAST VALUE DIFF BUS_0.22UF
J 2
(-7175 900);
DISPLAY 0.553191 (-7175 900);
FORCEPROP 2 LAST TOLERANCE 20%
J 2
(-7100 950);
DISPLAY 0.553191 (-7100 950);
DISPLAY INVISIBLE (-7100 950);
FORCEPROP 2 LAST PACK_TYPE C0201
J 2
(-7200 950);
DISPLAY 0.553191 (-7200 950);
DISPLAY INVISIBLE (-7200 950);
FORCEPROP 1 LAST MATERIAL X6S
J 2
(-7016 979);
DISPLAY 0.574468 (-7016 979);
PAINT GREEN (-7016 979);
DISPLAY INVISIBLE (-7016 979);
FORCEPROP 2 LAST VOLTAGE 6.3V
J 2
(-7375 950);
DISPLAY 0.553191 (-7375 950);
DISPLAY INVISIBLE (-7375 950);
FORCEPROP 1 LAST PIN_NAMES_ROTATE TRUE
J 2
(-7025 900);
DISPLAY 0.489362 (-7025 900);
PAINT GREEN (-7025 900);
DISPLAY INVISIBLE (-7025 900);
FORCEPROP 1 LAST CDS_LMAN_SYM_OUTLINE -25,50,25,-50
J 2
(-7025 900);
DISPLAY 0.468085 (-7025 900);
PAINT GREEN (-7025 900);
DISPLAY INVISIBLE (-7025 900);
FORCEPROP 2 LAST CDS_LIB pure_quanta
J 2
(-7025 900);
DISPLAY INVISIBLE (-7025 900);
FORCEPROP 1 LAST PATH I91
J 2
(-7025 900);
DISPLAY 0.723404 (-7025 900);
DISPLAY INVISIBLE (-7025 900);
FORCEPROP 1 LAST PART_NUMBER SP_CH4221MEE01
J 2
(-7141 988);
DISPLAY 0.574468 (-7141 988);
PAINT GREEN (-7141 988);
DISPLAY INVISIBLE (-7141 988);
FORCEPROP 1 LAST LOCATION C6753
J 0
(-6775 975);
DISPLAY 1.021277 (-6775 975);
DISPLAY INVISIBLE (-6775 975);
FORCEADD Q_CAP_DIFFBUS..2
R 2
(-7025 1050);
FORCEPROP 1 LAST LOCATION C6752
J 2
(-6750 1050);
DISPLAY 0.723404 (-6750 1050);
PAINT GREEN (-6750 1050);
FORCEPROP 2 LAST $SEC 1
J 2
(-6850 1125);
DISPLAY 0.680851 (-6850 1125);
PAINT MONO (-6850 1125);
DISPLAY INVISIBLE (-6850 1125);
FORCEPROP 2 LAST CDS_SEC 1
J 2
(-6850 1125);
DISPLAY 0.680851 (-6850 1125);
DISPLAY INVISIBLE (-6850 1125);
FORCEPROP 2 LASTPIN (-6950 1050) $PN 1
J 0
(-6940 1060);
DISPLAY 0.808511 (-6940 1060);
FORCEPROP 2 LASTPIN (-7100 1050) $PN 2
J 2
(-7110 1060);
DISPLAY 0.808511 (-7110 1060);
FORCEPROP 2 LAST VALUE DIFF BUS_0.22UF
J 2
(-7175 1050);
DISPLAY 0.553191 (-7175 1050);
FORCEPROP 2 LAST TOLERANCE 20%
J 2
(-7100 1100);
DISPLAY 0.553191 (-7100 1100);
DISPLAY INVISIBLE (-7100 1100);
FORCEPROP 2 LAST PACK_TYPE C0201
J 2
(-7200 1100);
DISPLAY 0.553191 (-7200 1100);
DISPLAY INVISIBLE (-7200 1100);
FORCEPROP 1 LAST MATERIAL X6S
J 2
(-7016 1129);
DISPLAY 0.574468 (-7016 1129);
PAINT GREEN (-7016 1129);
DISPLAY INVISIBLE (-7016 1129);
FORCEPROP 2 LAST VOLTAGE 6.3V
J 2
(-7375 1100);
DISPLAY 0.553191 (-7375 1100);
DISPLAY INVISIBLE (-7375 1100);
FORCEPROP 1 LAST PIN_NAMES_ROTATE TRUE
J 2
(-7025 1050);
DISPLAY 0.489362 (-7025 1050);
PAINT GREEN (-7025 1050);
DISPLAY INVISIBLE (-7025 1050);
FORCEPROP 2 LAST CDS_LIB pure_quanta
J 2
(-7025 1050);
DISPLAY INVISIBLE (-7025 1050);
FORCEPROP 1 LAST CDS_LMAN_SYM_OUTLINE -25,50,25,-50
J 2
(-7025 1050);
DISPLAY 0.468085 (-7025 1050);
PAINT GREEN (-7025 1050);
DISPLAY INVISIBLE (-7025 1050);
FORCEPROP 1 LAST PATH I92
J 2
(-7025 1050);
DISPLAY 0.723404 (-7025 1050);
DISPLAY INVISIBLE (-7025 1050);
FORCEPROP 1 LAST PART_NUMBER SP_CH4221MEE01
J 2
(-7141 1138);
DISPLAY 0.574468 (-7141 1138);
PAINT GREEN (-7141 1138);
DISPLAY INVISIBLE (-7141 1138);
FORCEPROP 1 LAST LOCATION C6752
J 0
(-6775 1125);
DISPLAY 1.021277 (-6775 1125);
DISPLAY INVISIBLE (-6775 1125);
FORCEADD Q_CAP_DIFFBUS..2
R 2
(-7025 1100);
FORCEPROP 1 LAST LOCATION C6751
J 2
(-6750 1100);
DISPLAY 0.723404 (-6750 1100);
PAINT GREEN (-6750 1100);
FORCEPROP 2 LAST $SEC 1
J 2
(-6850 1175);
DISPLAY 0.680851 (-6850 1175);
PAINT MONO (-6850 1175);
DISPLAY INVISIBLE (-6850 1175);
FORCEPROP 2 LAST CDS_SEC 1
J 2
(-6850 1175);
DISPLAY 0.680851 (-6850 1175);
DISPLAY INVISIBLE (-6850 1175);
FORCEPROP 2 LASTPIN (-6950 1100) $PN 1
J 0
(-6940 1110);
DISPLAY 0.808511 (-6940 1110);
FORCEPROP 2 LASTPIN (-7100 1100) $PN 2
J 2
(-7110 1110);
DISPLAY 0.808511 (-7110 1110);
FORCEPROP 2 LAST VALUE DIFF BUS_0.22UF
J 2
(-7175 1100);
DISPLAY 0.553191 (-7175 1100);
FORCEPROP 2 LAST TOLERANCE 20%
J 2
(-7100 1150);
DISPLAY 0.553191 (-7100 1150);
DISPLAY INVISIBLE (-7100 1150);
FORCEPROP 2 LAST PACK_TYPE C0201
J 2
(-7200 1150);
DISPLAY 0.553191 (-7200 1150);
DISPLAY INVISIBLE (-7200 1150);
FORCEPROP 1 LAST MATERIAL X6S
J 2
(-7016 1179);
DISPLAY 0.574468 (-7016 1179);
PAINT GREEN (-7016 1179);
DISPLAY INVISIBLE (-7016 1179);
FORCEPROP 2 LAST VOLTAGE 6.3V
J 2
(-7375 1150);
DISPLAY 0.553191 (-7375 1150);
DISPLAY INVISIBLE (-7375 1150);
FORCEPROP 1 LAST PIN_NAMES_ROTATE TRUE
J 2
(-7025 1100);
DISPLAY 0.489362 (-7025 1100);
PAINT GREEN (-7025 1100);
DISPLAY INVISIBLE (-7025 1100);
FORCEPROP 2 LAST CDS_LIB pure_quanta
J 2
(-7025 1100);
DISPLAY INVISIBLE (-7025 1100);
FORCEPROP 1 LAST CDS_LMAN_SYM_OUTLINE -25,50,25,-50
J 2
(-7025 1100);
DISPLAY 0.468085 (-7025 1100);
PAINT GREEN (-7025 1100);
DISPLAY INVISIBLE (-7025 1100);
FORCEPROP 1 LAST PATH I93
J 2
(-7025 1100);
DISPLAY 0.723404 (-7025 1100);
DISPLAY INVISIBLE (-7025 1100);
FORCEPROP 1 LAST PART_NUMBER SP_CH4221MEE01
J 2
(-7141 1188);
DISPLAY 0.574468 (-7141 1188);
PAINT GREEN (-7141 1188);
DISPLAY INVISIBLE (-7141 1188);
FORCEPROP 1 LAST LOCATION C6751
J 0
(-6775 1175);
DISPLAY 1.021277 (-6775 1175);
DISPLAY INVISIBLE (-6775 1175);
FORCEADD Q_CAP_DIFFBUS..2
R 2
(-7025 1250);
FORCEPROP 1 LAST LOCATION C6750
J 2
(-6750 1250);
DISPLAY 0.723404 (-6750 1250);
PAINT GREEN (-6750 1250);
FORCEPROP 2 LAST $SEC 1
J 2
(-6850 1325);
DISPLAY 0.680851 (-6850 1325);
PAINT MONO (-6850 1325);
DISPLAY INVISIBLE (-6850 1325);
FORCEPROP 2 LAST CDS_SEC 1
J 2
(-6850 1325);
DISPLAY 0.680851 (-6850 1325);
DISPLAY INVISIBLE (-6850 1325);
FORCEPROP 2 LASTPIN (-6950 1250) $PN 1
J 0
(-6940 1260);
DISPLAY 0.808511 (-6940 1260);
FORCEPROP 2 LASTPIN (-7100 1250) $PN 2
J 2
(-7110 1260);
DISPLAY 0.808511 (-7110 1260);
FORCEPROP 2 LAST VALUE DIFF BUS_0.22UF
J 2
(-7175 1250);
DISPLAY 0.553191 (-7175 1250);
FORCEPROP 2 LAST TOLERANCE 20%
J 2
(-7100 1300);
DISPLAY 0.553191 (-7100 1300);
DISPLAY INVISIBLE (-7100 1300);
FORCEPROP 2 LAST PACK_TYPE C0201
J 2
(-7200 1300);
DISPLAY 0.553191 (-7200 1300);
DISPLAY INVISIBLE (-7200 1300);
FORCEPROP 1 LAST MATERIAL X6S
J 2
(-7016 1329);
DISPLAY 0.574468 (-7016 1329);
PAINT GREEN (-7016 1329);
DISPLAY INVISIBLE (-7016 1329);
FORCEPROP 2 LAST VOLTAGE 6.3V
J 2
(-7375 1300);
DISPLAY 0.553191 (-7375 1300);
DISPLAY INVISIBLE (-7375 1300);
FORCEPROP 1 LAST PIN_NAMES_ROTATE TRUE
J 2
(-7025 1250);
DISPLAY 0.489362 (-7025 1250);
PAINT GREEN (-7025 1250);
DISPLAY INVISIBLE (-7025 1250);
FORCEPROP 1 LAST CDS_LMAN_SYM_OUTLINE -25,50,25,-50
J 2
(-7025 1250);
DISPLAY 0.468085 (-7025 1250);
PAINT GREEN (-7025 1250);
DISPLAY INVISIBLE (-7025 1250);
FORCEPROP 2 LAST CDS_LIB pure_quanta
J 2
(-7025 1250);
DISPLAY INVISIBLE (-7025 1250);
FORCEPROP 1 LAST PATH I94
J 2
(-7025 1250);
DISPLAY 0.723404 (-7025 1250);
DISPLAY INVISIBLE (-7025 1250);
FORCEPROP 1 LAST PART_NUMBER SP_CH4221MEE01
J 2
(-7141 1338);
DISPLAY 0.574468 (-7141 1338);
PAINT GREEN (-7141 1338);
DISPLAY INVISIBLE (-7141 1338);
FORCEPROP 1 LAST LOCATION C6750
J 0
(-6775 1325);
DISPLAY 1.021277 (-6775 1325);
DISPLAY INVISIBLE (-6775 1325);
FORCEADD Q_CAP_DIFFBUS..2
R 2
(-7025 1300);
FORCEPROP 1 LAST LOCATION C6749
J 2
(-6750 1300);
DISPLAY 0.723404 (-6750 1300);
PAINT GREEN (-6750 1300);
FORCEPROP 2 LAST $SEC 1
J 2
(-6850 1375);
DISPLAY 0.680851 (-6850 1375);
PAINT MONO (-6850 1375);
DISPLAY INVISIBLE (-6850 1375);
FORCEPROP 2 LAST CDS_SEC 1
J 2
(-6850 1375);
DISPLAY 0.680851 (-6850 1375);
DISPLAY INVISIBLE (-6850 1375);
FORCEPROP 2 LASTPIN (-6950 1300) $PN 1
J 0
(-6940 1310);
DISPLAY 0.808511 (-6940 1310);
FORCEPROP 2 LASTPIN (-7100 1300) $PN 2
J 2
(-7110 1310);
DISPLAY 0.808511 (-7110 1310);
FORCEPROP 2 LAST VALUE DIFF BUS_0.22UF
J 2
(-7175 1300);
DISPLAY 0.553191 (-7175 1300);
FORCEPROP 2 LAST TOLERANCE 20%
J 2
(-7100 1350);
DISPLAY 0.553191 (-7100 1350);
DISPLAY INVISIBLE (-7100 1350);
FORCEPROP 2 LAST PACK_TYPE C0201
J 2
(-7200 1350);
DISPLAY 0.553191 (-7200 1350);
DISPLAY INVISIBLE (-7200 1350);
FORCEPROP 1 LAST MATERIAL X6S
J 2
(-7016 1379);
DISPLAY 0.574468 (-7016 1379);
PAINT GREEN (-7016 1379);
DISPLAY INVISIBLE (-7016 1379);
FORCEPROP 2 LAST VOLTAGE 6.3V
J 2
(-7375 1350);
DISPLAY 0.553191 (-7375 1350);
DISPLAY INVISIBLE (-7375 1350);
FORCEPROP 1 LAST PIN_NAMES_ROTATE TRUE
J 2
(-7025 1300);
DISPLAY 0.489362 (-7025 1300);
PAINT GREEN (-7025 1300);
DISPLAY INVISIBLE (-7025 1300);
FORCEPROP 1 LAST CDS_LMAN_SYM_OUTLINE -25,50,25,-50
J 2
(-7025 1300);
DISPLAY 0.468085 (-7025 1300);
PAINT GREEN (-7025 1300);
DISPLAY INVISIBLE (-7025 1300);
FORCEPROP 2 LAST CDS_LIB pure_quanta
J 2
(-7025 1300);
DISPLAY INVISIBLE (-7025 1300);
FORCEPROP 1 LAST PATH I95
J 2
(-7025 1300);
DISPLAY 0.723404 (-7025 1300);
DISPLAY INVISIBLE (-7025 1300);
FORCEPROP 1 LAST PART_NUMBER SP_CH4221MEE01
J 2
(-7141 1388);
DISPLAY 0.574468 (-7141 1388);
PAINT GREEN (-7141 1388);
DISPLAY INVISIBLE (-7141 1388);
FORCEPROP 1 LAST LOCATION C6749
J 0
(-6775 1375);
DISPLAY 1.021277 (-6775 1375);
DISPLAY INVISIBLE (-6775 1375);
FORCEADD Q_CAP_DIFFBUS..2
R 2
(-7025 1450);
FORCEPROP 1 LAST LOCATION C6748
J 2
(-6750 1450);
DISPLAY 0.723404 (-6750 1450);
PAINT GREEN (-6750 1450);
FORCEPROP 2 LAST $SEC 1
J 2
(-6850 1525);
DISPLAY 0.680851 (-6850 1525);
PAINT MONO (-6850 1525);
DISPLAY INVISIBLE (-6850 1525);
FORCEPROP 2 LAST CDS_SEC 1
J 2
(-6850 1525);
DISPLAY 0.680851 (-6850 1525);
DISPLAY INVISIBLE (-6850 1525);
FORCEPROP 2 LASTPIN (-6950 1450) $PN 1
J 0
(-6940 1460);
DISPLAY 0.808511 (-6940 1460);
FORCEPROP 2 LASTPIN (-7100 1450) $PN 2
J 2
(-7110 1460);
DISPLAY 0.808511 (-7110 1460);
FORCEPROP 2 LAST VALUE DIFF BUS_0.22UF
J 2
(-7175 1450);
DISPLAY 0.553191 (-7175 1450);
FORCEPROP 2 LAST TOLERANCE 20%
J 2
(-7100 1500);
DISPLAY 0.553191 (-7100 1500);
DISPLAY INVISIBLE (-7100 1500);
FORCEPROP 2 LAST PACK_TYPE C0201
J 2
(-7200 1500);
DISPLAY 0.553191 (-7200 1500);
DISPLAY INVISIBLE (-7200 1500);
FORCEPROP 1 LAST MATERIAL X6S
J 2
(-7016 1529);
DISPLAY 0.574468 (-7016 1529);
PAINT GREEN (-7016 1529);
DISPLAY INVISIBLE (-7016 1529);
FORCEPROP 2 LAST VOLTAGE 6.3V
J 2
(-7375 1500);
DISPLAY 0.553191 (-7375 1500);
DISPLAY INVISIBLE (-7375 1500);
FORCEPROP 1 LAST PIN_NAMES_ROTATE TRUE
J 2
(-7025 1450);
DISPLAY 0.489362 (-7025 1450);
PAINT GREEN (-7025 1450);
DISPLAY INVISIBLE (-7025 1450);
FORCEPROP 2 LAST CDS_LIB pure_quanta
J 2
(-7025 1450);
DISPLAY INVISIBLE (-7025 1450);
FORCEPROP 1 LAST CDS_LMAN_SYM_OUTLINE -25,50,25,-50
J 2
(-7025 1450);
DISPLAY 0.468085 (-7025 1450);
PAINT GREEN (-7025 1450);
DISPLAY INVISIBLE (-7025 1450);
FORCEPROP 1 LAST PATH I96
J 2
(-7025 1450);
DISPLAY 0.723404 (-7025 1450);
DISPLAY INVISIBLE (-7025 1450);
FORCEPROP 1 LAST PART_NUMBER SP_CH4221MEE01
J 2
(-7141 1538);
DISPLAY 0.574468 (-7141 1538);
PAINT GREEN (-7141 1538);
DISPLAY INVISIBLE (-7141 1538);
FORCEPROP 1 LAST LOCATION C6748
J 0
(-6775 1525);
DISPLAY 1.021277 (-6775 1525);
DISPLAY INVISIBLE (-6775 1525);
FORCEADD Q_CAP_DIFFBUS..2
R 2
(-7025 1500);
FORCEPROP 1 LAST LOCATION C6747
J 2
(-6750 1500);
DISPLAY 0.723404 (-6750 1500);
PAINT GREEN (-6750 1500);
FORCEPROP 2 LAST $SEC 1
J 2
(-6850 1575);
DISPLAY 0.680851 (-6850 1575);
PAINT MONO (-6850 1575);
DISPLAY INVISIBLE (-6850 1575);
FORCEPROP 2 LAST CDS_SEC 1
J 2
(-6850 1575);
DISPLAY 0.680851 (-6850 1575);
DISPLAY INVISIBLE (-6850 1575);
FORCEPROP 2 LASTPIN (-6950 1500) $PN 1
J 0
(-6940 1510);
DISPLAY 0.808511 (-6940 1510);
FORCEPROP 2 LASTPIN (-7100 1500) $PN 2
J 2
(-7110 1510);
DISPLAY 0.808511 (-7110 1510);
FORCEPROP 2 LAST VALUE DIFF BUS_0.22UF
J 2
(-7175 1500);
DISPLAY 0.553191 (-7175 1500);
FORCEPROP 2 LAST TOLERANCE 20%
J 2
(-7100 1550);
DISPLAY 0.553191 (-7100 1550);
DISPLAY INVISIBLE (-7100 1550);
FORCEPROP 2 LAST PACK_TYPE C0201
J 2
(-7200 1550);
DISPLAY 0.553191 (-7200 1550);
DISPLAY INVISIBLE (-7200 1550);
FORCEPROP 1 LAST MATERIAL X6S
J 2
(-7016 1579);
DISPLAY 0.574468 (-7016 1579);
PAINT GREEN (-7016 1579);
DISPLAY INVISIBLE (-7016 1579);
FORCEPROP 2 LAST VOLTAGE 6.3V
J 2
(-7375 1550);
DISPLAY 0.553191 (-7375 1550);
DISPLAY INVISIBLE (-7375 1550);
FORCEPROP 1 LAST PIN_NAMES_ROTATE TRUE
J 2
(-7025 1500);
DISPLAY 0.489362 (-7025 1500);
PAINT GREEN (-7025 1500);
DISPLAY INVISIBLE (-7025 1500);
FORCEPROP 2 LAST CDS_LIB pure_quanta
J 2
(-7025 1500);
DISPLAY INVISIBLE (-7025 1500);
FORCEPROP 1 LAST CDS_LMAN_SYM_OUTLINE -25,50,25,-50
J 2
(-7025 1500);
DISPLAY 0.468085 (-7025 1500);
PAINT GREEN (-7025 1500);
DISPLAY INVISIBLE (-7025 1500);
FORCEPROP 1 LAST PATH I97
J 2
(-7025 1500);
DISPLAY 0.723404 (-7025 1500);
DISPLAY INVISIBLE (-7025 1500);
FORCEPROP 1 LAST PART_NUMBER SP_CH4221MEE01
J 2
(-7141 1588);
DISPLAY 0.574468 (-7141 1588);
PAINT GREEN (-7141 1588);
DISPLAY INVISIBLE (-7141 1588);
FORCEPROP 1 LAST LOCATION C6747
J 0
(-6775 1575);
DISPLAY 1.021277 (-6775 1575);
DISPLAY INVISIBLE (-6775 1575);
FORCEADD Q_CAP_DIFFBUS..2
R 2
(-7025 1650);
FORCEPROP 1 LAST LOCATION C6746
J 2
(-6750 1650);
DISPLAY 0.723404 (-6750 1650);
PAINT GREEN (-6750 1650);
FORCEPROP 2 LAST $SEC 1
J 2
(-6850 1725);
DISPLAY 0.680851 (-6850 1725);
PAINT MONO (-6850 1725);
DISPLAY INVISIBLE (-6850 1725);
FORCEPROP 2 LAST CDS_SEC 1
J 2
(-6850 1725);
DISPLAY 0.680851 (-6850 1725);
DISPLAY INVISIBLE (-6850 1725);
FORCEPROP 2 LASTPIN (-6950 1650) $PN 1
J 0
(-6940 1660);
DISPLAY 0.808511 (-6940 1660);
FORCEPROP 2 LASTPIN (-7100 1650) $PN 2
J 2
(-7110 1660);
DISPLAY 0.808511 (-7110 1660);
FORCEPROP 2 LAST VALUE DIFF BUS_0.22UF
J 2
(-7175 1650);
DISPLAY 0.553191 (-7175 1650);
FORCEPROP 2 LAST TOLERANCE 20%
J 2
(-7100 1700);
DISPLAY 0.553191 (-7100 1700);
DISPLAY INVISIBLE (-7100 1700);
FORCEPROP 2 LAST PACK_TYPE C0201
J 2
(-7200 1700);
DISPLAY 0.553191 (-7200 1700);
DISPLAY INVISIBLE (-7200 1700);
FORCEPROP 1 LAST MATERIAL X6S
J 2
(-7016 1729);
DISPLAY 0.574468 (-7016 1729);
PAINT GREEN (-7016 1729);
DISPLAY INVISIBLE (-7016 1729);
FORCEPROP 2 LAST VOLTAGE 6.3V
J 2
(-7375 1700);
DISPLAY 0.553191 (-7375 1700);
DISPLAY INVISIBLE (-7375 1700);
FORCEPROP 1 LAST PIN_NAMES_ROTATE TRUE
J 2
(-7025 1650);
DISPLAY 0.489362 (-7025 1650);
PAINT GREEN (-7025 1650);
DISPLAY INVISIBLE (-7025 1650);
FORCEPROP 2 LAST CDS_LIB pure_quanta
J 2
(-7025 1650);
DISPLAY INVISIBLE (-7025 1650);
FORCEPROP 1 LAST CDS_LMAN_SYM_OUTLINE -25,50,25,-50
J 2
(-7025 1650);
DISPLAY 0.468085 (-7025 1650);
PAINT GREEN (-7025 1650);
DISPLAY INVISIBLE (-7025 1650);
FORCEPROP 1 LAST PATH I98
J 2
(-7025 1650);
DISPLAY 0.723404 (-7025 1650);
DISPLAY INVISIBLE (-7025 1650);
FORCEPROP 1 LAST PART_NUMBER SP_CH4221MEE01
J 2
(-7141 1738);
DISPLAY 0.574468 (-7141 1738);
PAINT GREEN (-7141 1738);
DISPLAY INVISIBLE (-7141 1738);
FORCEPROP 1 LAST LOCATION C6746
J 0
(-6775 1725);
DISPLAY 1.021277 (-6775 1725);
DISPLAY INVISIBLE (-6775 1725);
FORCEADD Q_CAP_DIFFBUS..2
R 2
(-7025 1700);
FORCEPROP 1 LAST LOCATION C6745
J 2
(-6750 1700);
DISPLAY 0.723404 (-6750 1700);
PAINT GREEN (-6750 1700);
FORCEPROP 2 LAST $SEC 1
J 2
(-6850 1775);
DISPLAY 0.680851 (-6850 1775);
PAINT MONO (-6850 1775);
DISPLAY INVISIBLE (-6850 1775);
FORCEPROP 2 LAST CDS_SEC 1
J 2
(-6850 1775);
DISPLAY 0.680851 (-6850 1775);
DISPLAY INVISIBLE (-6850 1775);
FORCEPROP 2 LASTPIN (-6950 1700) $PN 1
J 0
(-6940 1710);
DISPLAY 0.808511 (-6940 1710);
FORCEPROP 2 LASTPIN (-7100 1700) $PN 2
J 2
(-7110 1710);
DISPLAY 0.808511 (-7110 1710);
FORCEPROP 2 LAST VALUE DIFF BUS_0.22UF
J 2
(-7175 1700);
DISPLAY 0.553191 (-7175 1700);
FORCEPROP 2 LAST TOLERANCE 20%
J 2
(-7100 1750);
DISPLAY 0.553191 (-7100 1750);
DISPLAY INVISIBLE (-7100 1750);
FORCEPROP 2 LAST PACK_TYPE C0201
J 2
(-7200 1750);
DISPLAY 0.553191 (-7200 1750);
DISPLAY INVISIBLE (-7200 1750);
FORCEPROP 1 LAST MATERIAL X6S
J 2
(-7016 1779);
DISPLAY 0.574468 (-7016 1779);
PAINT GREEN (-7016 1779);
DISPLAY INVISIBLE (-7016 1779);
FORCEPROP 2 LAST VOLTAGE 6.3V
J 2
(-7375 1750);
DISPLAY 0.553191 (-7375 1750);
DISPLAY INVISIBLE (-7375 1750);
FORCEPROP 1 LAST PIN_NAMES_ROTATE TRUE
J 2
(-7025 1700);
DISPLAY 0.489362 (-7025 1700);
PAINT GREEN (-7025 1700);
DISPLAY INVISIBLE (-7025 1700);
FORCEPROP 2 LAST CDS_LIB pure_quanta
J 2
(-7025 1700);
DISPLAY INVISIBLE (-7025 1700);
FORCEPROP 1 LAST CDS_LMAN_SYM_OUTLINE -25,50,25,-50
J 2
(-7025 1700);
DISPLAY 0.468085 (-7025 1700);
PAINT GREEN (-7025 1700);
DISPLAY INVISIBLE (-7025 1700);
FORCEPROP 1 LAST PATH I99
J 2
(-7025 1700);
DISPLAY 0.723404 (-7025 1700);
DISPLAY INVISIBLE (-7025 1700);
FORCEPROP 1 LAST PART_NUMBER SP_CH4221MEE01
J 2
(-7141 1788);
DISPLAY 0.574468 (-7141 1788);
PAINT GREEN (-7141 1788);
DISPLAY INVISIBLE (-7141 1788);
FORCEPROP 1 LAST LOCATION C6745
J 0
(-6775 1775);
DISPLAY 1.021277 (-6775 1775);
DISPLAY INVISIBLE (-6775 1775);
FORCEADD QUANTA_TITLE_BLOCK_C..1
(0 0);
FORCEPROP 0 LAST CDS_CON_LAST_MODIFIED Thu Sep 14 16:12:56 2023
J 0
(-1885 15);
DISPLAY INVISIBLE (-1885 15);
FORCEPROP 1 LAST CUSTOM_TXT_CDS <CON_LAST_MODIFIED>
J 0
(-1885 15);
DISPLAY 0.978723 (-1885 15);
FORCEPROP 2 LAST CUSTOM_TXT_CDS <XR_PAGE_TITLE>
J 0
(-7890 5250);
DISPLAY 0.638298 (-7890 5250);
PAINT PINK (-7890 5250);
DISPLAY INVISIBLE (-7890 5250);
FORCEPROP 1 LAST CUSTOM_TXT_CDS <NAME_2>
J 0
(-3175 50);
FORCEPROP 1 LAST CUSTOM_TXT_CDS <NAME_1>
J 0
(-3175 175);
FORCEPROP 1 LAST CUSTOM_TXT_CDS <Q_NUMBER>
J 0
(-1403 103);
DISPLAY 1.212766 (-1403 103);
FORCEPROP 1 LAST CUSTOM_TXT_CDS <Q_PROJ>
J 0
(-2382 102);
DISPLAY 1.212766 (-2382 102);
FORCEPROP 1 LAST CUSTOM_TXT_CDS <Q_REV>
J 0
(-184 103);
DISPLAY 1.212766 (-184 103);
FORCEPROP 1 LAST CUSTOM_TXT_CDS <CON_PAGE_NUM> OF <CON_TOTAL_PAGES>
J 0
(-446 18);
DISPLAY 0.978723 (-446 18);
FORCEPROP 1 LAST Q_TITLE RETIMER_CPU1_P3(4)
J 0
(-9366 26);
DISPLAY 2.446809 (-9366 26);
PAINT GREEN (-9366 26);
FORCEPROP 2 LAST PAGE_BORDER TRUE
J 0
(-7890 5250);
DISPLAY 0.638298 (-7890 5250);
PAINT PINK (-7890 5250);
DISPLAY INVISIBLE (-7890 5250);
FORCEPROP 2 LAST CDS_LIB pure_quanta
J 0
(0 0);
DISPLAY INVISIBLE (0 0);
FORCEPROP 1 LAST CDS_LMAN_SYM_OUTLINE -9475,6775,100,-125
J 0
(0 0);
DISPLAY 0.468085 (0 0);
PAINT GREEN (0 0);
DISPLAY INVISIBLE (0 0);
FORCEPROP 2 LAST CDS_XR_PAGE_TITLE CR-353 : @T6G_MB_LIB.T6G(SCH_1):PAGE353
J 0
(-7890 5250);
DISPLAY 0.638298 (-7890 5250);
PAINT PINK (-7890 5250);
DISPLAY INVISIBLE (-7890 5250);
FORCEPROP 1 LAST Q_DEPT BU9
J 1
(-3763 49);
DISPLAY 1.957447 (-3763 49);
PAINT GREEN (-3763 49);
DISPLAY INVISIBLE (-3763 49);
FORCEPROP 1 LAST COMMENT_BODY TRUE
J 0
(12 -13);
DISPLAY 0.978723 (12 -13);
PAINT GREEN (12 -13);
DISPLAY INVISIBLE (12 -13);
WIRE 17 -1 (-1650 1400)(-1650 1600);
WIRE 17 -1 (-1650 1400)(-1650 1200);
WIRE 17 -1 (-1650 1800)(-1650 1600);
WIRE 17 -1 (-1650 2000)(-1650 1800);
WIRE 17 -1 (-1650 1200)(-1650 1000);
WIRE 17 -1 (-1650 1000)(-1650 800);
WIRE 17 -1 (-1650 2200)(-1650 2000);
FORCEPROP 2 LAST SIG_NAME P5E_CPU1_P3_TX_BUF_C_DN<7:0>
J 0
(-1660 2210);
DISPLAY 0.680851 (-1660 2210);
PAINT WHITE (-1660 2210);
WIRE 17 -1 (-3475 800)(-3475 1000);
WIRE 17 -1 (-3475 1000)(-3475 1200);
WIRE 17 -1 (-3475 1200)(-3475 1400);
WIRE 17 -1 (-3475 1400)(-3475 1600);
WIRE 17 -1 (-3475 1600)(-3475 1800);
WIRE 17 -1 (-3475 1800)(-3475 2000);
WIRE 17 -1 (-3475 2000)(-3475 2200);
WIRE 17 -1 (-4325 2200)(-3475 2200);
FORCEPROP 2 LAST SIG_NAME P5E_CPU1_P3_TX_BUF_DN<7:0>
J 0
(-4310 2210);
DISPLAY 0.680851 (-4310 2210);
PAINT WHITE (-4310 2210);
WIRE 17 -1 (-3225 1050)(-3225 850);
WIRE 17 -1 (-3225 1250)(-3225 1050);
WIRE 17 -1 (-3225 1450)(-3225 1250);
WIRE 17 -1 (-3225 1450)(-3225 1650);
WIRE 17 -1 (-3225 1850)(-3225 1650);
WIRE 17 -1 (-3225 2050)(-3225 1850);
WIRE 17 -1 (-3225 2250)(-3225 2050);
WIRE 17 -1 (-4325 2250)(-3225 2250);
FORCEPROP 2 LAST SIG_NAME P5E_CPU1_P3_TX_BUF_DP<7:0>
J 0
(-4310 2260);
DISPLAY 0.680851 (-4310 2260);
PAINT WHITE (-4310 2260);
WIRE 17 -1 (-1850 1050)(-1850 850);
WIRE 17 -1 (-1850 1250)(-1850 1050);
WIRE 17 -1 (-1850 1450)(-1850 1250);
WIRE 17 -1 (-1850 1450)(-1850 1650);
WIRE 17 -1 (-1850 1850)(-1850 1650);
WIRE 17 -1 (-1850 2050)(-1850 1850);
WIRE 17 -1 (-1850 2250)(-1850 2050);
WIRE 17 -1 (-1850 2250)(-750 2250);
FORCEPROP 2 LAST SIG_NAME P5E_CPU1_P3_TX_BUF_C_DP<7:0>
J 0
(-1660 2260);
DISPLAY 0.680851 (-1660 2260);
PAINT WHITE (-1660 2260);
WIRE 17 -1 (-8050 675)(-8050 875);
WIRE 17 -1 (-8050 875)(-8050 1075);
WIRE 17 -1 (-8050 1075)(-8050 1275);
WIRE 17 -1 (-8050 1275)(-8050 1475);
WIRE 17 -1 (-8050 1475)(-8050 1675);
WIRE 17 -1 (-8050 1675)(-8050 1875);
WIRE 17 -1 (-8050 1875)(-8050 2075);
WIRE 17 -1 (-8900 2075)(-8050 2075);
FORCEPROP 2 LAST SIG_NAME P5E_CPU1_P3_TX_BUF_DN<15:8>
J 0
(-8885 2085);
DISPLAY 0.680851 (-8885 2085);
PAINT WHITE (-8885 2085);
WIRE 17 -1 (-7800 925)(-7800 725);
WIRE 17 -1 (-7800 1125)(-7800 925);
WIRE 17 -1 (-7800 1325)(-7800 1125);
WIRE 17 -1 (-7800 1325)(-7800 1525);
WIRE 17 -1 (-7800 1725)(-7800 1525);
WIRE 17 -1 (-7800 1925)(-7800 1725);
WIRE 17 -1 (-7800 2125)(-7800 1925);
WIRE 17 -1 (-8900 2125)(-7800 2125);
FORCEPROP 2 LAST SIG_NAME P5E_CPU1_P3_TX_BUF_DP<15:8>
J 0
(-8885 2135);
DISPLAY 0.680851 (-8885 2135);
PAINT WHITE (-8885 2135);
WIRE 17 -1 (-6225 875)(-6225 675);
WIRE 17 -1 (-6225 1075)(-6225 875);
WIRE 17 -1 (-6225 1275)(-6225 1075);
WIRE 17 -1 (-6225 1275)(-6225 1475);
WIRE 17 -1 (-6225 1675)(-6225 1475);
WIRE 17 -1 (-6225 1875)(-6225 1675);
WIRE 17 -1 (-6225 2075)(-6225 1875);
FORCEPROP 2 LAST SIG_NAME P5E_CPU1_P3_TX_BUF_C_DN<15:8>
J 0
(-6235 2085);
DISPLAY 0.680851 (-6235 2085);
PAINT WHITE (-6235 2085);
WIRE 17 -1 (-6425 925)(-6425 725);
WIRE 17 -1 (-6425 1125)(-6425 925);
WIRE 17 -1 (-6425 1325)(-6425 1125);
WIRE 17 -1 (-6425 1325)(-6425 1525);
WIRE 17 -1 (-6425 1725)(-6425 1525);
WIRE 17 -1 (-6425 1925)(-6425 1725);
WIRE 17 -1 (-6425 2125)(-6425 1925);
WIRE 17 -1 (-6425 2125)(-5325 2125);
FORCEPROP 2 LAST SIG_NAME P5E_CPU1_P3_TX_BUF_C_DP<15:8>
J 0
(-6235 2135);
DISPLAY 0.680851 (-6235 2135);
PAINT WHITE (-6235 2135);
WIRE 17 -1 (-1625 5675)(-1625 5325);
WIRE 17 -1 (-1625 5675)(-750 5675);
FORCEPROP 2 LAST SIG_NAME P5E_CPU1_P3_TX_BUF_DN<7:0>
J 0
(-1635 5685);
DISPLAY 0.680851 (-1635 5685);
PAINT WHITE (-1635 5685);
WIRE 17 -1 (-1825 5775)(-1825 5425);
WIRE 17 -1 (-1825 5775)(-725 5775);
FORCEPROP 2 LAST SIG_NAME P5E_CPU1_P3_TX_BUF_DP<7:0>
J 0
(-1635 5785);
DISPLAY 0.680851 (-1635 5785);
PAINT WHITE (-1635 5785);
WIRE 17 -1 (-1825 5425)(-1825 5075);
WIRE 17 -1 (-1825 5075)(-1825 4725);
WIRE 17 -1 (-1825 4375)(-1825 4725);
WIRE 17 -1 (-1625 5325)(-1625 4975);
WIRE 17 -1 (-1625 4975)(-1625 4625);
WIRE 17 -1 (-1625 4275)(-1625 4625);
WIRE 17 -1 (-1625 4275)(-1625 3925);
WIRE 17 -1 (-1625 3925)(-1625 3575);
WIRE 17 -1 (-1625 3575)(-1625 3225);
WIRE 17 -1 (-1825 3675)(-1825 3325);
WIRE 17 -1 (-1825 4025)(-1825 3675);
WIRE 17 -1 (-1825 4375)(-1825 4025);
WIRE 17 -1 (-6800 3600)(-6800 3250);
WIRE 17 -1 (-6800 3950)(-6800 3600);
WIRE 17 -1 (-6800 4300)(-6800 3950);
WIRE 17 -1 (-6800 4300)(-6800 4650);
WIRE 17 -1 (-6800 5000)(-6800 4650);
WIRE 17 -1 (-6800 5350)(-6800 5000);
WIRE 17 -1 (-6800 5700)(-6800 5350);
FORCEPROP 2 LAST SIG_NAME P5E_CPU1_P3_TX_BUF_DN<15:8>
J 0
(-6810 5710);
DISPLAY 0.680851 (-6810 5710);
PAINT WHITE (-6810 5710);
WIRE 17 -1 (-7000 5100)(-7000 4750);
WIRE 17 -1 (-7000 5450)(-7000 5100);
WIRE 17 -1 (-7000 4400)(-7000 4750);
WIRE 17 -1 (-7000 4400)(-7000 4050);
WIRE 17 -1 (-7000 5800)(-7000 5450);
WIRE 17 -1 (-7000 5800)(-5900 5800);
FORCEPROP 2 LAST SIG_NAME P5E_CPU1_P3_TX_BUF_DP<15:8>
J 0
(-6810 5810);
DISPLAY 0.680851 (-6810 5810);
PAINT WHITE (-6810 5810);
WIRE 17 -1 (-7000 3700)(-7000 3350);
WIRE 17 -1 (-7000 4050)(-7000 3700);
WIRE 17 -1 (-1650 2200)(-750 2200);
WIRE 17 -1 (-6225 2075)(-5325 2075);
WIRE 17 -1 (-6800 5700)(-5925 5700);
WIRE 16 -1 (-7325 3575)(-6900 3575);
WIRE 16 -1 (-7325 3675)(-7100 3675);
WIRE 16 -1 (-7325 4375)(-7100 4375);
WIRE 16 -1 (-7325 5675)(-6900 5675);
WIRE 16 -1 (-7325 5775)(-7100 5775);
WIRE 16 -1 (-7325 5075)(-7100 5075);
WIRE 16 -1 (-7325 4025)(-7100 4025);
WIRE 16 -1 (-2150 3900)(-1725 3900);
WIRE 16 -1 (-2150 3550)(-1725 3550);
WIRE 16 -1 (-2150 3200)(-1725 3200);
WIRE 16 -1 (-2150 3650)(-1925 3650);
WIRE 16 -1 (-2150 4000)(-1925 4000);
WIRE 16 -1 (-2150 5750)(-1925 5750);
WIRE 16 -1 (-2150 4700)(-1925 4700);
WIRE 16 -1 (-2150 4350)(-1925 4350);
WIRE 16 -1 (-2150 4600)(-1725 4600);
WIRE 16 -1 (-7325 4975)(-6900 4975);
WIRE 16 -1 (-7325 5325)(-6900 5325);
WIRE 16 -1 (-7325 5425)(-7100 5425);
WIRE 16 -1 (-7325 3325)(-7100 3325);
WIRE 16 -1 (-7325 3925)(-6900 3925);
WIRE 16 -1 (-7325 4275)(-6900 4275);
WIRE 16 -1 (-7325 4625)(-6900 4625);
WIRE 16 -1 (-7325 4725)(-7100 4725);
WIRE 16 -1 (-7325 3225)(-6900 3225);
WIRE 16 -1 (-2150 5650)(-1725 5650);
WIRE 16 -1 (-2150 3300)(-1925 3300);
WIRE 16 -1 (-2150 4250)(-1725 4250);
WIRE 16 -1 (-2150 4950)(-1725 4950);
WIRE 16 -1 (-2150 5050)(-1925 5050);
WIRE 16 -1 (-2150 5400)(-1925 5400);
WIRE 16 -1 (-2150 5300)(-1725 5300);
WIRE 16 -1 (-6950 2100)(-6525 2100);
WIRE 16 -1 (-7100 2100)(-7700 2100);
WIRE 16 -1 (-6950 2050)(-6325 2050);
WIRE 16 -1 (-7100 2050)(-7950 2050);
WIRE 16 -1 (-6950 1900)(-6525 1900);
WIRE 16 -1 (-6950 1850)(-6325 1850);
WIRE 16 -1 (-6950 1700)(-6525 1700);
WIRE 16 -1 (-6950 1650)(-6325 1650);
WIRE 16 -1 (-6950 1450)(-6325 1450);
WIRE 16 -1 (-6950 1500)(-6525 1500);
WIRE 16 -1 (-6950 1300)(-6525 1300);
WIRE 16 -1 (-6950 1250)(-6325 1250);
WIRE 16 -1 (-6950 1100)(-6525 1100);
WIRE 16 -1 (-6950 1050)(-6325 1050);
WIRE 16 -1 (-6950 900)(-6525 900);
WIRE 16 -1 (-6950 850)(-6325 850);
WIRE 16 -1 (-6950 700)(-6525 700);
WIRE 16 -1 (-6950 650)(-6325 650);
WIRE 16 -1 (-7100 1900)(-7700 1900);
WIRE 16 -1 (-7100 1700)(-7700 1700);
WIRE 16 -1 (-7100 1850)(-7950 1850);
WIRE 16 -1 (-7100 1650)(-7950 1650);
WIRE 16 -1 (-7100 1500)(-7700 1500);
WIRE 16 -1 (-7100 1300)(-7700 1300);
WIRE 16 -1 (-7100 1100)(-7700 1100);
WIRE 16 -1 (-7100 1250)(-7950 1250);
WIRE 16 -1 (-7100 1050)(-7950 1050);
WIRE 16 -1 (-7100 1450)(-7950 1450);
WIRE 16 -1 (-7100 900)(-7700 900);
WIRE 16 -1 (-7100 700)(-7700 700);
WIRE 16 -1 (-7100 850)(-7950 850);
WIRE 16 -1 (-7100 650)(-7950 650);
WIRE 16 -1 (-2375 2225)(-1950 2225);
WIRE 16 -1 (-2375 2175)(-1750 2175);
WIRE 16 -1 (-2525 2225)(-3125 2225);
WIRE 16 -1 (-2525 2175)(-3375 2175);
WIRE 16 -1 (-2375 2025)(-1950 2025);
WIRE 16 -1 (-2525 2025)(-3125 2025);
WIRE 16 -1 (-2375 1975)(-1750 1975);
WIRE 16 -1 (-2375 1825)(-1950 1825);
WIRE 16 -1 (-2375 1775)(-1750 1775);
WIRE 16 -1 (-2375 1625)(-1950 1625);
WIRE 16 -1 (-2375 1425)(-1950 1425);
WIRE 16 -1 (-2375 1375)(-1750 1375);
WIRE 16 -1 (-2375 1175)(-1750 1175);
WIRE 16 -1 (-2375 1225)(-1950 1225);
WIRE 16 -1 (-2375 1025)(-1950 1025);
WIRE 16 -1 (-2375 975)(-1750 975);
WIRE 16 -1 (-2375 825)(-1950 825);
WIRE 16 -1 (-2375 775)(-1750 775);
WIRE 16 -1 (-2525 1825)(-3125 1825);
WIRE 16 -1 (-2525 1625)(-3125 1625);
WIRE 16 -1 (-2525 1425)(-3125 1425);
WIRE 16 -1 (-2525 1225)(-3125 1225);
WIRE 16 -1 (-2525 1025)(-3125 1025);
WIRE 16 -1 (-2525 1775)(-3375 1775);
WIRE 16 -1 (-2525 1975)(-3375 1975);
WIRE 16 -1 (-2525 1575)(-3375 1575);
WIRE 16 -1 (-2525 1375)(-3375 1375);
WIRE 16 -1 (-2525 1175)(-3375 1175);
WIRE 16 -1 (-2525 825)(-3125 825);
WIRE 16 -1 (-2525 975)(-3375 975);
WIRE 16 -1 (-2525 775)(-3375 775);
WIRE 16 -1 (-2375 1575)(-1750 1575);
FORCENOTE
RETIMER TO EXAMAX
(-8675 2875) 0;
DISPLAY LEFT (-8675 2875);
DISPLAY 3.148936 (-8675 2875);
FORCENOTE
RETIMER TO EXAMAX
(-3675 2850) 0;
DISPLAY LEFT (-3675 2850);
DISPLAY 3.148936 (-3675 2850);
QUIT
